FILE_TYPE = MACRO_DRAWING;
SET COLOR_WIRE YELLOW;
SET COLOR_PROP MONO;
SET COLOR_DOT WHITE;
SET COLOR_ARC YELLOW;
SET COLOR_BODY GREEN;
SET COLOR_NOTE MONO;
SET PROP_DISPLAY VALUE;
SET PAGE_NUMBER P223;
FORCEADD OFFPAGE..2
(4125 1750);
FORCEPROP 2 LAST $XR0 223 
J 0
(4314 1750);
DISPLAY 0.638298 (4314 1750);
PAINT MONO (4314 1750);
FORCEPROP 2 LAST ROOM VDDQ_GHJ_PWR_VR
J 0
(3700 1825);
DISPLAY 1.361702 (3700 1825);
PAINT ORANGE (3700 1825);
DISPLAY INVISIBLE (3700 1825);
FORCEPROP 1 LAST COMMENT_BODY TRUE
J 0
(4080 1655);
DISPLAY 1.170213 (4080 1655);
PAINT GREEN (4080 1655);
DISPLAY INVISIBLE (4080 1655);
FORCEPROP 2 LAST CDS_LIB mstr_standard
J 0
(4125 1750);
PAINT ORANGE (4125 1750);
DISPLAY INVISIBLE (4125 1750);
FORCEPROP 2 LAST PATH I1
J 0
(4300 1825);
DISPLAY 1.021277 (4300 1825);
PAINT ORANGE (4300 1825);
DISPLAY INVISIBLE (4300 1825);
FORCEPROP 1 LAST OFFPAGE TRUE
J 0
(4450 1625);
DISPLAY 1.170213 (4450 1625);
PAINT GREEN (4450 1625);
DISPLAY INVISIBLE (4450 1625);
FORCEADD OFFPAGE..2
(4275 2450);
FORCEPROP 2 LAST $XR0 94 
J 0
(4464 2450);
DISPLAY 0.638298 (4464 2450);
PAINT MONO (4464 2450);
FORCEPROP 2 LAST $XR1 119 
J 0
(4554 2450);
DISPLAY 0.638298 (4554 2450);
PAINT MONO (4554 2450);
FORCEPROP 2 LAST $XR2 144 
J 0
(4674 2450);
DISPLAY 0.638298 (4674 2450);
PAINT MONO (4674 2450);
FORCEPROP 2 LAST ROOM VDDQ_GHJ_PWR_VR
J 0
(3850 2525);
DISPLAY 1.361702 (3850 2525);
PAINT ORANGE (3850 2525);
DISPLAY INVISIBLE (3850 2525);
FORCEPROP 1 LAST COMMENT_BODY TRUE
J 0
(4230 2355);
DISPLAY 1.170213 (4230 2355);
PAINT GREEN (4230 2355);
DISPLAY INVISIBLE (4230 2355);
FORCEPROP 2 LAST CDS_LIB mstr_standard
J 0
(4275 2450);
PAINT ORANGE (4275 2450);
DISPLAY INVISIBLE (4275 2450);
FORCEPROP 1 LAST OFFPAGE TRUE
J 0
(4600 2325);
DISPLAY 1.170213 (4600 2325);
PAINT GREEN (4600 2325);
DISPLAY INVISIBLE (4600 2325);
FORCEPROP 2 LAST PATH I10
J 0
(4450 2525);
DISPLAY 1.021277 (4450 2525);
PAINT ORANGE (4450 2525);
DISPLAY INVISIBLE (4450 2525);
FORCEADD OFFPAGE..2
(4100 2550);
FORCEPROP 2 LAST $XR0 229 
J 0
(4289 2550);
DISPLAY 0.638298 (4289 2550);
PAINT MONO (4289 2550);
FORCEPROP 1 LAST COMMENT_BODY TRUE
J 0
(4055 2455);
DISPLAY 1.170213 (4055 2455);
PAINT GREEN (4055 2455);
DISPLAY INVISIBLE (4055 2455);
FORCEPROP 2 LAST ROOM VDDQ_GHJ_PWR_VR
J 0
(3675 2625);
DISPLAY 1.361702 (3675 2625);
PAINT ORANGE (3675 2625);
DISPLAY INVISIBLE (3675 2625);
FORCEPROP 1 LAST OFFPAGE TRUE
J 0
(4425 2425);
DISPLAY 1.170213 (4425 2425);
PAINT GREEN (4425 2425);
DISPLAY INVISIBLE (4425 2425);
FORCEPROP 2 LAST CDS_LIB mstr_standard
J 0
(4100 2550);
PAINT ORANGE (4100 2550);
DISPLAY INVISIBLE (4100 2550);
FORCEPROP 2 LAST PATH I11
J 0
(4275 2625);
DISPLAY 1.021277 (4275 2625);
PAINT ORANGE (4275 2625);
DISPLAY INVISIBLE (4275 2625);
FORCEADD RES..2
(2700 3100);
FORCEPROP 1 LASTPIN (2700 3000) $PN 2
J 0
(2705 3010);
DISPLAY 0.617021 (2705 3010);
PAINT ORANGE (2705 3010);
FORCEPROP 1 LAST PACK_TYPE 0402
J 0
(2740 2925);
DISPLAY 0.617021 (2740 2925);
PAINT SKYBLUE (2740 2925);
FORCEPROP 1 LAST PART_NUMBER G21796-311
J 0
(2740 2975);
DISPLAY 0.617021 (2740 2975);
PAINT BLUE (2740 2975);
FORCEPROP 1 LAST MATERIAL EMPTY
J 0
(2740 3025);
DISPLAY 0.617021 (2740 3025);
PAINT RED (2740 3025);
FORCEPROP 1 LASTPIN (2700 3200) $PN 1
J 0
(2705 3162);
DISPLAY 0.617021 (2705 3162);
PAINT ORANGE (2705 3162);
FORCEPROP 1 LAST WATTAGE 1/16W
J 0
(2740 3075);
DISPLAY 0.617021 (2740 3075);
PAINT SKYBLUE (2740 3075);
FORCEPROP 1 LAST TOLERANCE 1.0%
J 0
(2745 3125);
DISPLAY 0.617021 (2745 3125);
PAINT SKYBLUE (2745 3125);
FORCEPROP 1 LAST VALUE 2.26K
J 0
(2745 3175);
DISPLAY 0.617021 (2745 3175);
PAINT SKYBLUE (2745 3175);
FORCEPROP 1 LAST LOCATION R1G6
J 0
(2745 3225);
DISPLAY 0.617021 (2745 3225);
PAINT AQUA (2745 3225);
FORCEPROP 2 LAST ROOM VDDQ_GHJ_PWR_VR
J 0
(2750 3075);
DISPLAY 1.361702 (2750 3075);
PAINT ORANGE (2750 3075);
DISPLAY INVISIBLE (2750 3075);
FORCEPROP 2 LAST CDS_LIB mstr_discrete
J 0
(2700 3100);
PAINT ORANGE (2700 3100);
DISPLAY INVISIBLE (2700 3100);
FORCEPROP 1 LAST PATH I13
J 0
(2750 3275);
DISPLAY 0.978723 (2750 3275);
PAINT WHITE (2750 3275);
DISPLAY INVISIBLE (2750 3275);
FORCEPROP 2 LAST CDS_LOCATION R1G6
J 0
(2745 3225);
DISPLAY 0.617021 (2745 3225);
PAINT AQUA (2745 3225);
DISPLAY INVISIBLE (2745 3225);
FORCEPROP 2 LAST SEC 1
J 0
(2750 3350);
DISPLAY 0.680851 (2750 3350);
PAINT MONO (2750 3350);
DISPLAY INVISIBLE (2750 3350);
FORCEPROP 2 LAST SEC_TYPE 0402
J 0
(2750 3350);
DISPLAY 1.021277 (2750 3350);
PAINT ORANGE (2750 3350);
DISPLAY INVISIBLE (2750 3350);
FORCEADD RES..1
(3275 2550);
FORCEPROP 1 LAST WATTAGE 1/16W
J 2
(3150 2625);
DISPLAY 0.617021 (3150 2625);
PAINT SKYBLUE (3150 2625);
FORCEPROP 1 LAST PACK_TYPE 0402
J 0
(3025 2675);
DISPLAY 0.617021 (3025 2675);
PAINT SKYBLUE (3025 2675);
FORCEPROP 1 LAST TOLERANCE 1.0%
J 0
(3375 2550);
DISPLAY 0.617021 (3375 2550);
PAINT SKYBLUE (3375 2550);
FORCEPROP 1 LAST MATERIAL CHIP
J 0
(3375 2600);
DISPLAY 0.617021 (3375 2600);
PAINT SKYBLUE (3375 2600);
FORCEPROP 1 LAST VALUE 22.1
J 2
(3200 2575);
DISPLAY 0.617021 (3200 2575);
PAINT SKYBLUE (3200 2575);
FORCEPROP 1 LAST PART_NUMBER G21796-250
J 0
(3225 2650);
DISPLAY 0.617021 (3225 2650);
PAINT BLUE (3225 2650);
FORCEPROP 1 LAST LOCATION R1G12
J 0
(3225 2600);
DISPLAY 0.617021 (3225 2600);
PAINT AQUA (3225 2600);
FORCEPROP 2 LAST CDS_LIB mstr_discrete
J 0
(3275 2550);
PAINT MONO (3275 2550);
DISPLAY INVISIBLE (3275 2550);
FORCEPROP 1 LASTPIN (3175 2550) $PN 1
J 0
(3187 2562);
DISPLAY 0.787234 (3187 2562);
PAINT ORANGE (3187 2562);
DISPLAY INVISIBLE (3187 2562);
FORCEPROP 1 LASTPIN (3375 2550) $PN 2
J 0
(3337 2562);
DISPLAY 0.787234 (3337 2562);
PAINT ORANGE (3337 2562);
DISPLAY INVISIBLE (3337 2562);
FORCEPROP 2 LAST ROOM VDDQ_GHJ_PWR_VR
J 0
(3225 2650);
DISPLAY 1.361702 (3225 2650);
PAINT ORANGE (3225 2650);
DISPLAY INVISIBLE (3225 2650);
FORCEPROP 1 LAST PATH I14
J 0
(3225 2700);
DISPLAY 0.978723 (3225 2700);
PAINT WHITE (3225 2700);
DISPLAY INVISIBLE (3225 2700);
FORCEPROP 2 LAST CDS_LOCATION R1G12
J 0
(3225 2600);
DISPLAY 0.617021 (3225 2600);
PAINT AQUA (3225 2600);
DISPLAY INVISIBLE (3225 2600);
FORCEPROP 2 LAST $SEC 1
J 0
(3225 2750);
PAINT MONO (3225 2750);
DISPLAY INVISIBLE (3225 2750);
FORCEPROP 2 LAST CDS_SEC 1
J 0
(3225 2750);
PAINT MONO (3225 2750);
DISPLAY INVISIBLE (3225 2750);
FORCEADD P3V3_STBY..1
(2475 3800);
FORCEPROP 3 LASTPIN (2475 3750) SIG_NAME P3V3_STBY\g
J 0
(2485 3760);
DISPLAY 0.659574 (2485 3760);
PAINT MONO (2485 3760);
DISPLAY INVISIBLE (2485 3760);
FORCEPROP 1 LAST HDL_POWER P3V3_STBY
J 0
(2175 3675);
DISPLAY 0.872340 (2175 3675);
PAINT ORANGE (2175 3675);
DISPLAY INVISIBLE (2175 3675);
FORCEPROP 1 LAST PATH I15
J 0
(2520 3802);
DISPLAY 0.340426 (2520 3802);
PAINT GREEN (2520 3802);
DISPLAY INVISIBLE (2520 3802);
FORCEPROP 1 LAST BODY_TYPE PLUMBING
J 0
(2430 3757);
DISPLAY 0.340426 (2430 3757);
PAINT GREEN (2430 3757);
DISPLAY INVISIBLE (2430 3757);
FORCEPROP 2 LAST CDS_LIB mstr_symbols
J 0
(2475 3800);
PAINT ORANGE (2475 3800);
DISPLAY INVISIBLE (2475 3800);
FORCEPROP 1 LAST SIZE 1B
J 0
(2520 3822);
DISPLAY 0.340426 (2520 3822);
PAINT GREEN (2520 3822);
DISPLAY INVISIBLE (2520 3822);
FORCEPROP 1 LAST VOLTAGE 3.3V
J 0
(2430 3757);
DISPLAY 0.340426 (2430 3757);
PAINT SKYBLUE (2430 3757);
DISPLAY INVISIBLE (2430 3757);
FORCEADD RES..1
(2875 2400);
FORCEPROP 1 LAST WATTAGE 1/16W
J 2
(2775 2350);
DISPLAY 0.617021 (2775 2350);
PAINT SKYBLUE (2775 2350);
FORCEPROP 1 LASTPIN (2775 2400) $PN 1
J 0
(2787 2412);
DISPLAY 0.617021 (2787 2412);
PAINT ORANGE (2787 2412);
FORCEPROP 1 LAST VALUE 0.0
J 2
(2850 2350);
DISPLAY 0.617021 (2850 2350);
PAINT SKYBLUE (2850 2350);
FORCEPROP 1 LAST PART_NUMBER G21497-005
J 0
(2725 2300);
DISPLAY 0.617021 (2725 2300);
PAINT BLUE (2725 2300);
FORCEPROP 1 LAST TOLERANCE 5%
J 0
(2875 2350);
DISPLAY 0.617021 (2875 2350);
PAINT SKYBLUE (2875 2350);
FORCEPROP 1 LAST LOCATION R1G9
J 0
(2825 2450);
DISPLAY 0.617021 (2825 2450);
PAINT AQUA (2825 2450);
FORCEPROP 1 LASTPIN (2975 2400) $PN 2
J 0
(2937 2412);
DISPLAY 0.617021 (2937 2412);
PAINT ORANGE (2937 2412);
FORCEPROP 1 LAST PACK_TYPE 0402
J 0
(2975 2350);
DISPLAY 0.617021 (2975 2350);
PAINT SKYBLUE (2975 2350);
FORCEPROP 1 LAST MATERIAL CHIP
J 0
(3100 2350);
DISPLAY 0.617021 (3100 2350);
PAINT SKYBLUE (3100 2350);
FORCEPROP 2 LAST ROOM VDDQ_GHJ_PWR_VR
J 0
(2825 2500);
DISPLAY 1.361702 (2825 2500);
PAINT ORANGE (2825 2500);
DISPLAY INVISIBLE (2825 2500);
FORCEPROP 2 LAST CDS_LOCATION R1G9
J 0
(2825 2450);
DISPLAY 0.617021 (2825 2450);
PAINT AQUA (2825 2450);
DISPLAY INVISIBLE (2825 2450);
FORCEPROP 2 LAST CDS_LIB mstr_discrete
J 0
(2875 2400);
PAINT ORANGE (2875 2400);
DISPLAY INVISIBLE (2875 2400);
FORCEPROP 1 LAST PATH I16
J 0
(2825 2550);
DISPLAY 0.978723 (2825 2550);
PAINT WHITE (2825 2550);
DISPLAY INVISIBLE (2825 2550);
FORCEPROP 2 LAST SEC 1
J 0
(2825 2625);
DISPLAY 0.680851 (2825 2625);
PAINT MONO (2825 2625);
DISPLAY INVISIBLE (2825 2625);
FORCEPROP 2 LAST SEC_TYPE 0402
J 0
(2825 2625);
DISPLAY 1.021277 (2825 2625);
PAINT ORANGE (2825 2625);
DISPLAY INVISIBLE (2825 2625);
FORCEADD RES..2
(2400 3100);
FORCEPROP 1 LAST PACK_TYPE 0402
J 0
(2440 2925);
DISPLAY 0.617021 (2440 2925);
PAINT SKYBLUE (2440 2925);
FORCEPROP 1 LAST MATERIAL CHIP
J 0
(2440 3025);
DISPLAY 0.617021 (2440 3025);
PAINT SKYBLUE (2440 3025);
FORCEPROP 1 LASTPIN (2400 3000) $PN 2
J 0
(2405 3010);
DISPLAY 0.617021 (2405 3010);
PAINT ORANGE (2405 3010);
FORCEPROP 1 LAST PART_NUMBER G21796-026
J 0
(2440 2975);
DISPLAY 0.617021 (2440 2975);
PAINT BLUE (2440 2975);
FORCEPROP 1 LASTPIN (2400 3200) $PN 1
J 0
(2405 3162);
DISPLAY 0.617021 (2405 3162);
PAINT ORANGE (2405 3162);
FORCEPROP 1 LAST TOLERANCE 1%
J 0
(2445 3125);
DISPLAY 0.617021 (2445 3125);
PAINT SKYBLUE (2445 3125);
FORCEPROP 1 LAST WATTAGE 1/16W
J 0
(2440 3075);
DISPLAY 0.617021 (2440 3075);
PAINT SKYBLUE (2440 3075);
FORCEPROP 1 LAST VALUE 1.00K
J 0
(2445 3175);
DISPLAY 0.617021 (2445 3175);
PAINT SKYBLUE (2445 3175);
FORCEPROP 1 LAST LOCATION R1G16
J 0
(2445 3225);
DISPLAY 0.617021 (2445 3225);
PAINT AQUA (2445 3225);
FORCEPROP 2 LAST CDS_LIB mstr_discrete
J 2
(2400 3100);
PAINT ORANGE (2400 3100);
DISPLAY INVISIBLE (2400 3100);
FORCEPROP 2 LAST CDS_LOCATION R1G16
J 0
(2445 3225);
DISPLAY 0.617021 (2445 3225);
PAINT AQUA (2445 3225);
DISPLAY INVISIBLE (2445 3225);
FORCEPROP 1 LAST PATH I17
J 0
(2450 3275);
DISPLAY 0.978723 (2450 3275);
PAINT WHITE (2450 3275);
DISPLAY INVISIBLE (2450 3275);
FORCEPROP 2 LAST ROOM VDDQ_GHJ_PWR_VR
J 0
(2450 3275);
DISPLAY 1.361702 (2450 3275);
PAINT ORANGE (2450 3275);
DISPLAY INVISIBLE (2450 3275);
FORCEPROP 2 LAST SEC_TYPE 0402
J 0
(2450 3350);
DISPLAY 1.021277 (2450 3350);
PAINT ORANGE (2450 3350);
DISPLAY INVISIBLE (2450 3350);
FORCEPROP 2 LAST SEC 1
J 0
(2450 3350);
DISPLAY 0.680851 (2450 3350);
PAINT MONO (2450 3350);
DISPLAY INVISIBLE (2450 3350);
FORCEADD OFFPAGE..1
R 2
(4100 2050);
FORCEPROP 2 LAST $XR0 138 
J 0
(4286 2050);
DISPLAY 0.638298 (4286 2050);
PAINT MONO (4286 2050);
FORCEPROP 2 LAST $XR1 159 
J 0
(4406 2050);
DISPLAY 0.638298 (4406 2050);
PAINT MONO (4406 2050);
FORCEPROP 2 LAST $XR2 211 
J 0
(4526 2050);
DISPLAY 0.638298 (4526 2050);
PAINT MONO (4526 2050);
FORCEPROP 2 LAST $XR3 213 
J 0
(4646 2050);
DISPLAY 0.638298 (4646 2050);
PAINT MONO (4646 2050);
FORCEPROP 2 LAST $XR4 235 
J 0
(4766 2050);
DISPLAY 0.638298 (4766 2050);
PAINT MONO (4766 2050);
FORCEPROP 2 LAST $XR5 193 
J 0
(4886 2050);
DISPLAY 0.638298 (4886 2050);
PAINT MONO (4886 2050);
FORCEPROP 2 LAST $XR6 194 
J 0
(5006 2050);
DISPLAY 0.638298 (5006 2050);
PAINT MONO (5006 2050);
FORCEPROP 2 LAST $XR7 201 
J 0
(5126 2050);
DISPLAY 0.638298 (5126 2050);
PAINT MONO (5126 2050);
FORCEPROP 2 LAST $XR8 206 
J 0
(4286 2014);
DISPLAY 0.638298 (4286 2014);
PAINT MONO (4286 2014);
FORCEPROP 2 LAST $XR9 215 
J 0
(4406 2014);
DISPLAY 0.638298 (4406 2014);
PAINT MONO (4406 2014);
FORCEPROP 2 LAST $XR10 218 
J 0
(4526 2014);
DISPLAY 0.638298 (4526 2014);
PAINT MONO (4526 2014);
FORCEPROP 2 LAST $XR11 226 
J 0
(4646 2014);
DISPLAY 0.638298 (4646 2014);
PAINT MONO (4646 2014);
FORCEPROP 1 LAST OFFPAGE TRUE
J 2
(3775 1925);
DISPLAY 1.170213 (3775 1925);
PAINT GREEN (3775 1925);
DISPLAY INVISIBLE (3775 1925);
FORCEPROP 1 LAST COMMENT_BODY TRUE
J 2
(3975 1950);
DISPLAY 1.170213 (3975 1950);
PAINT GREEN (3975 1950);
DISPLAY INVISIBLE (3975 1950);
FORCEPROP 2 LAST ROOM VDDQ_GHJ_PWR_VR
J 0
(3675 2125);
DISPLAY 1.361702 (3675 2125);
PAINT ORANGE (3675 2125);
DISPLAY INVISIBLE (3675 2125);
FORCEPROP 2 LAST PATH I18
J 0
(4275 2125);
DISPLAY 1.021277 (4275 2125);
PAINT ORANGE (4275 2125);
DISPLAY INVISIBLE (4275 2125);
FORCEPROP 2 LAST CDS_LIB mstr_standard
J 0
(4100 2050);
PAINT ORANGE (4100 2050);
DISPLAY INVISIBLE (4100 2050);
FORCEADD OFFPAGE..3
(4100 2000);
FORCEPROP 2 LAST $XR0 138 
J 0
(4764 2000);
DISPLAY 0.638298 (4764 2000);
PAINT MONO (4764 2000);
FORCEPROP 2 LAST $XR1 159 
J 0
(4884 2000);
DISPLAY 0.638298 (4884 2000);
PAINT MONO (4884 2000);
FORCEPROP 2 LAST $XR2 193 
J 0
(5004 2000);
DISPLAY 0.638298 (5004 2000);
PAINT MONO (5004 2000);
FORCEPROP 2 LAST $XR3 194 
J 0
(5124 2000);
DISPLAY 0.638298 (5124 2000);
PAINT MONO (5124 2000);
FORCEPROP 2 LAST $XR4 201 
J 0
(4764 1964);
DISPLAY 0.638298 (4764 1964);
PAINT MONO (4764 1964);
FORCEPROP 2 LAST $XR5 206 
J 0
(4884 1964);
DISPLAY 0.638298 (4884 1964);
PAINT MONO (4884 1964);
FORCEPROP 2 LAST $XR6 211 
J 0
(5004 1964);
DISPLAY 0.638298 (5004 1964);
PAINT MONO (5004 1964);
FORCEPROP 2 LAST $XR7 213 
J 0
(5124 1964);
DISPLAY 0.638298 (5124 1964);
PAINT MONO (5124 1964);
FORCEPROP 2 LAST $XR8 215 
J 0
(4764 1928);
DISPLAY 0.638298 (4764 1928);
PAINT MONO (4764 1928);
FORCEPROP 2 LAST $XR9 218 
J 0
(4884 1928);
DISPLAY 0.638298 (4884 1928);
PAINT MONO (4884 1928);
FORCEPROP 2 LAST $XR10 226 
J 0
(5004 1928);
DISPLAY 0.638298 (5004 1928);
PAINT MONO (5004 1928);
FORCEPROP 2 LAST $XR11 235 
J 0
(5124 1928);
DISPLAY 0.638298 (5124 1928);
PAINT MONO (5124 1928);
FORCEPROP 1 LAST COMMENT_BODY TRUE
J 0
(4050 1900);
DISPLAY 1.170213 (4050 1900);
PAINT GREEN (4050 1900);
DISPLAY INVISIBLE (4050 1900);
FORCEPROP 2 LAST ROOM VDDQ_GHJ_PWR_VR
J 0
(3700 2075);
DISPLAY 1.361702 (3700 2075);
PAINT ORANGE (3700 2075);
DISPLAY INVISIBLE (3700 2075);
FORCEPROP 2 LAST CDS_LIB mstr_standard
J 0
(4100 2000);
PAINT ORANGE (4100 2000);
DISPLAY INVISIBLE (4100 2000);
FORCEPROP 1 LAST OFFPAGE TRUE
J 0
(4425 1875);
DISPLAY 1.170213 (4425 1875);
PAINT GREEN (4425 1875);
DISPLAY INVISIBLE (4425 1875);
FORCEPROP 2 LAST PATH I19
J 0
(4300 2075);
DISPLAY 1.021277 (4300 2075);
PAINT ORANGE (4300 2075);
DISPLAY INVISIBLE (4300 2075);
FORCEADD OFFPAGE..2
(4125 1500);
FORCEPROP 2 LAST $XR0 224 
J 0
(4314 1500);
DISPLAY 0.638298 (4314 1500);
PAINT MONO (4314 1500);
FORCEPROP 1 LAST COMMENT_BODY TRUE
J 0
(4080 1405);
DISPLAY 1.170213 (4080 1405);
PAINT GREEN (4080 1405);
DISPLAY INVISIBLE (4080 1405);
FORCEPROP 2 LAST ROOM VDDQ_GHJ_PWR_VR
J 0
(3700 1575);
DISPLAY 1.361702 (3700 1575);
PAINT ORANGE (3700 1575);
DISPLAY INVISIBLE (3700 1575);
FORCEPROP 1 LAST OFFPAGE TRUE
J 0
(4450 1375);
DISPLAY 1.170213 (4450 1375);
PAINT GREEN (4450 1375);
DISPLAY INVISIBLE (4450 1375);
FORCEPROP 2 LAST CDS_LIB mstr_standard
J 0
(4125 1500);
PAINT ORANGE (4125 1500);
DISPLAY INVISIBLE (4125 1500);
FORCEPROP 2 LAST PATH I2
J 0
(4300 1575);
DISPLAY 1.021277 (4300 1575);
PAINT ORANGE (4300 1575);
DISPLAY INVISIBLE (4300 1575);
FORCEADD OFFPAGE..3
(4100 1700);
FORCEPROP 2 LAST $XR0 55 
J 0
(4314 1700);
DISPLAY 0.638298 (4314 1700);
PAINT MONO (4314 1700);
FORCEPROP 2 LAST $XR1 193 
J 0
(4404 1700);
DISPLAY 0.638298 (4404 1700);
PAINT MONO (4404 1700);
FORCEPROP 2 LAST $XR2 226 
J 0
(4524 1700);
DISPLAY 0.638298 (4524 1700);
PAINT MONO (4524 1700);
FORCEPROP 2 LAST ROOM VDDQ_GHJ_PWR_VR
J 0
(3700 1775);
DISPLAY 1.361702 (3700 1775);
PAINT ORANGE (3700 1775);
DISPLAY INVISIBLE (3700 1775);
FORCEPROP 1 LAST COMMENT_BODY TRUE
J 0
(4050 1600);
DISPLAY 1.170213 (4050 1600);
PAINT GREEN (4050 1600);
DISPLAY INVISIBLE (4050 1600);
FORCEPROP 2 LAST CDS_LIB mstr_standard
J 0
(4100 1700);
PAINT ORANGE (4100 1700);
DISPLAY INVISIBLE (4100 1700);
FORCEPROP 2 LAST PATH I20
J 0
(4300 1775);
DISPLAY 1.021277 (4300 1775);
PAINT ORANGE (4300 1775);
DISPLAY INVISIBLE (4300 1775);
FORCEPROP 1 LAST OFFPAGE TRUE
J 0
(4425 1575);
DISPLAY 1.170213 (4425 1575);
PAINT GREEN (4425 1575);
DISPLAY INVISIBLE (4425 1575);
FORCEADD RES..1
(3175 2050);
FORCEPROP 1 LAST WATTAGE 1/16W
J 2
(3150 1900);
DISPLAY 0.617021 (3150 1900);
PAINT SKYBLUE (3150 1900);
FORCEPROP 1 LAST VALUE 0.0
J 2
(3150 1950);
DISPLAY 0.617021 (3150 1950);
PAINT SKYBLUE (3150 1950);
FORCEPROP 1 LAST MATERIAL CHIP
J 0
(3175 1900);
DISPLAY 0.617021 (3175 1900);
PAINT SKYBLUE (3175 1900);
FORCEPROP 1 LAST PACK_TYPE 0402
J 0
(3175 1850);
DISPLAY 0.617021 (3175 1850);
PAINT SKYBLUE (3175 1850);
FORCEPROP 1 LAST TOLERANCE 5%
J 0
(3175 1950);
DISPLAY 0.617021 (3175 1950);
PAINT SKYBLUE (3175 1950);
FORCEPROP 1 LAST LOCATION R1G19
J 0
(3125 2100);
DISPLAY 0.617021 (3125 2100);
PAINT AQUA (3125 2100);
FORCEPROP 1 LAST PART_NUMBER G21497-005
J 0
(3125 2150);
DISPLAY 0.617021 (3125 2150);
PAINT BLUE (3125 2150);
FORCEPROP 2 LAST CDS_LIB mstr_discrete
J 0
(3175 2050);
PAINT ORANGE (3175 2050);
DISPLAY INVISIBLE (3175 2050);
FORCEPROP 1 LASTPIN (3075 2050) $PN 1
J 0
(3087 2062);
DISPLAY 0.787234 (3087 2062);
PAINT ORANGE (3087 2062);
DISPLAY INVISIBLE (3087 2062);
FORCEPROP 2 LAST ROOM VDDQ_GHJ_PWR_VR
J 0
(3125 2150);
DISPLAY 1.361702 (3125 2150);
PAINT ORANGE (3125 2150);
DISPLAY INVISIBLE (3125 2150);
FORCEPROP 1 LAST PATH I21
J 0
(3125 2200);
DISPLAY 0.978723 (3125 2200);
PAINT WHITE (3125 2200);
DISPLAY INVISIBLE (3125 2200);
FORCEPROP 2 LAST CDS_LOCATION R1G19
J 0
(3125 2100);
DISPLAY 0.617021 (3125 2100);
PAINT AQUA (3125 2100);
DISPLAY INVISIBLE (3125 2100);
FORCEPROP 2 LAST $SEC 1
J 0
(3125 2250);
PAINT MONO (3125 2250);
DISPLAY INVISIBLE (3125 2250);
FORCEPROP 2 LAST CDS_SEC 1
J 0
(3125 2250);
PAINT MONO (3125 2250);
DISPLAY INVISIBLE (3125 2250);
FORCEPROP 1 LASTPIN (3275 2050) $PN 2
J 0
(3237 2062);
DISPLAY 0.787234 (3237 2062);
PAINT ORANGE (3237 2062);
DISPLAY INVISIBLE (3237 2062);
FORCEADD RES..1
(2850 2000);
FORCEPROP 1 LAST WATTAGE 1/16W
J 2
(2825 1850);
DISPLAY 0.617021 (2825 1850);
PAINT SKYBLUE (2825 1850);
FORCEPROP 1 LAST VALUE 0.0
J 2
(2825 1900);
DISPLAY 0.617021 (2825 1900);
PAINT SKYBLUE (2825 1900);
FORCEPROP 1 LAST MATERIAL CHIP
J 0
(2850 1850);
DISPLAY 0.617021 (2850 1850);
PAINT SKYBLUE (2850 1850);
FORCEPROP 1 LAST PACK_TYPE 0402
J 0
(2850 1800);
DISPLAY 0.617021 (2850 1800);
PAINT SKYBLUE (2850 1800);
FORCEPROP 1 LAST TOLERANCE 5%
J 0
(2850 1900);
DISPLAY 0.617021 (2850 1900);
PAINT SKYBLUE (2850 1900);
FORCEPROP 1 LAST LOCATION R1G21
J 0
(2800 2050);
DISPLAY 0.617021 (2800 2050);
PAINT AQUA (2800 2050);
FORCEPROP 1 LAST PART_NUMBER G21497-005
J 0
(2800 2100);
DISPLAY 0.617021 (2800 2100);
PAINT BLUE (2800 2100);
FORCEPROP 1 LASTPIN (2750 2000) $PN 1
J 0
(2762 2012);
DISPLAY 0.787234 (2762 2012);
PAINT ORANGE (2762 2012);
DISPLAY INVISIBLE (2762 2012);
FORCEPROP 1 LASTPIN (2950 2000) $PN 2
J 0
(2912 2012);
DISPLAY 0.787234 (2912 2012);
PAINT ORANGE (2912 2012);
DISPLAY INVISIBLE (2912 2012);
FORCEPROP 2 LAST CDS_LIB mstr_discrete
J 0
(2850 2000);
PAINT ORANGE (2850 2000);
DISPLAY INVISIBLE (2850 2000);
FORCEPROP 2 LAST CDS_LOCATION R1G21
J 0
(2800 2050);
DISPLAY 0.617021 (2800 2050);
PAINT AQUA (2800 2050);
DISPLAY INVISIBLE (2800 2050);
FORCEPROP 2 LAST CDS_SEC 1
J 0
(2800 2200);
PAINT MONO (2800 2200);
DISPLAY INVISIBLE (2800 2200);
FORCEPROP 2 LAST $SEC 1
J 0
(2800 2200);
PAINT MONO (2800 2200);
DISPLAY INVISIBLE (2800 2200);
FORCEPROP 1 LAST PATH I22
J 0
(2800 2150);
DISPLAY 0.978723 (2800 2150);
PAINT WHITE (2800 2150);
DISPLAY INVISIBLE (2800 2150);
FORCEPROP 2 LAST ROOM VDDQ_GHJ_PWR_VR
J 0
(2800 2100);
DISPLAY 1.361702 (2800 2100);
PAINT ORANGE (2800 2100);
DISPLAY INVISIBLE (2800 2100);
FORCEADD RES..1
(2850 1700);
FORCEPROP 1 LAST VALUE 0.0
J 2
(2750 1600);
DISPLAY 0.617021 (2750 1600);
PAINT SKYBLUE (2750 1600);
FORCEPROP 1 LASTPIN (2750 1700) $PN 1
J 0
(2762 1712);
DISPLAY 0.617021 (2762 1712);
PAINT ORANGE (2762 1712);
FORCEPROP 1 LAST WATTAGE 1/16W
J 2
(2825 1550);
DISPLAY 0.617021 (2825 1550);
PAINT SKYBLUE (2825 1550);
FORCEPROP 1 LAST TOLERANCE 5%
J 0
(2800 1600);
DISPLAY 0.617021 (2800 1600);
PAINT SKYBLUE (2800 1600);
FORCEPROP 1 LAST PART_NUMBER G21497-005
J 0
(2700 1650);
DISPLAY 0.617021 (2700 1650);
PAINT BLUE (2700 1650);
FORCEPROP 1 LAST LOCATION R1G10
J 0
(2800 1750);
DISPLAY 0.617021 (2800 1750);
PAINT AQUA (2800 1750);
FORCEPROP 1 LASTPIN (2950 1700) $PN 2
J 0
(2912 1712);
DISPLAY 0.617021 (2912 1712);
PAINT ORANGE (2912 1712);
FORCEPROP 1 LAST MATERIAL CHIP
J 0
(2850 1550);
DISPLAY 0.617021 (2850 1550);
PAINT SKYBLUE (2850 1550);
FORCEPROP 1 LAST PACK_TYPE 0402
J 0
(2925 1600);
DISPLAY 0.617021 (2925 1600);
PAINT SKYBLUE (2925 1600);
FORCEPROP 2 LAST CDS_LOCATION R1G10
J 0
(2800 1750);
DISPLAY 0.617021 (2800 1750);
PAINT AQUA (2800 1750);
DISPLAY INVISIBLE (2800 1750);
FORCEPROP 2 LAST SEC_TYPE 0402
J 0
(2800 1900);
DISPLAY 1.021277 (2800 1900);
PAINT ORANGE (2800 1900);
DISPLAY INVISIBLE (2800 1900);
FORCEPROP 2 LAST SEC 1
J 0
(2800 1900);
DISPLAY 0.680851 (2800 1900);
PAINT MONO (2800 1900);
DISPLAY INVISIBLE (2800 1900);
FORCEPROP 1 LAST PATH I23
J 0
(2800 1850);
DISPLAY 0.978723 (2800 1850);
PAINT WHITE (2800 1850);
DISPLAY INVISIBLE (2800 1850);
FORCEPROP 2 LAST ROOM VDDQ_GHJ_PWR_VR
J 0
(2800 1800);
DISPLAY 1.361702 (2800 1800);
PAINT ORANGE (2800 1800);
DISPLAY INVISIBLE (2800 1800);
FORCEPROP 2 LAST CDS_LIB mstr_discrete
J 0
(2850 1700);
PAINT ORANGE (2850 1700);
DISPLAY INVISIBLE (2850 1700);
FORCEADD GND..1
(2075 825);
FORCEPROP 3 LASTPIN (2075 875) SIG_NAME GND\g
J 0
(2085 885);
DISPLAY 0.659574 (2085 885);
PAINT MONO (2085 885);
DISPLAY INVISIBLE (2085 885);
FORCEPROP 2 LAST ROOM VDDQ_GHJ_PWR_VR
J 0
(1500 900);
DISPLAY 1.361702 (1500 900);
PAINT ORANGE (1500 900);
DISPLAY INVISIBLE (1500 900);
FORCEPROP 1 LAST BODY_TYPE PLUMBING
J 0
(2030 782);
DISPLAY 0.340426 (2030 782);
PAINT GREEN (2030 782);
DISPLAY INVISIBLE (2030 782);
FORCEPROP 1 LAST VOLTAGE 0
J 0
(2075 825);
PAINT SKYBLUE (2075 825);
DISPLAY INVISIBLE (2075 825);
FORCEPROP 1 LAST SIZE 1B
J 0
(2150 775);
DISPLAY 1.170213 (2150 775);
PAINT AQUA (2150 775);
DISPLAY INVISIBLE (2150 775);
FORCEPROP 2 LAST CDS_LIB mstr_symbols
J 0
(2075 825);
PAINT ORANGE (2075 825);
DISPLAY INVISIBLE (2075 825);
FORCEPROP 1 LAST PATH I24
J 0
(2150 825);
DISPLAY 0.872340 (2150 825);
PAINT AQUA (2150 825);
DISPLAY INVISIBLE (2150 825);
FORCEPROP 1 LAST HDL_POWER GND
J 0
(2075 975);
DISPLAY 1.170213 (2075 975);
PAINT GREEN (2075 975);
DISPLAY INVISIBLE (2075 975);
FORCEADD CAP_A..1
(1600 3100);
FORCEPROP 1 LAST MATERIAL X6S
J 0
(1650 3000);
DISPLAY 0.617021 (1650 3000);
PAINT SKYBLUE (1650 3000);
FORCEPROP 1 LAST PART_NUMBER D97712-004
J 0
(1650 2950);
DISPLAY 0.617021 (1650 2950);
PAINT BLUE (1650 2950);
FORCEPROP 1 LAST PACK_TYPE 0402V
J 0
(1650 2900);
DISPLAY 0.617021 (1650 2900);
PAINT SKYBLUE (1650 2900);
FORCEPROP 1 LAST TOLERANCE 10%
J 0
(1650 3050);
DISPLAY 0.617021 (1650 3050);
PAINT SKYBLUE (1650 3050);
FORCEPROP 1 LAST VOLTAGE 6.3V
J 0
(1650 3100);
DISPLAY 0.617021 (1650 3100);
PAINT SKYBLUE (1650 3100);
FORCEPROP 1 LAST VALUE 1.0UF
J 0
(1650 3150);
DISPLAY 0.617021 (1650 3150);
PAINT SKYBLUE (1650 3150);
FORCEPROP 1 LAST LOCATION C1G27
J 0
(1650 3200);
DISPLAY 0.617021 (1650 3200);
PAINT AQUA (1650 3200);
FORCEPROP 1 LASTPIN (1600 3000) $PN 2
J 0
(1610 2980);
DISPLAY 0.787234 (1610 2980);
PAINT ORANGE (1610 2980);
DISPLAY INVISIBLE (1610 2980);
FORCEPROP 2 LAST CDS_LOCATION C1G27
J 0
(1650 3200);
DISPLAY 0.617021 (1650 3200);
PAINT AQUA (1650 3200);
DISPLAY INVISIBLE (1650 3200);
FORCEPROP 2 LAST CDS_LIB dev_discrete
J 0
(1600 3100);
PAINT ORANGE (1600 3100);
DISPLAY INVISIBLE (1600 3100);
FORCEPROP 1 LAST PATH I25
J 0
(1650 3250);
DISPLAY 0.978723 (1650 3250);
PAINT WHITE (1650 3250);
DISPLAY INVISIBLE (1650 3250);
FORCEPROP 2 LAST ROOM VDDQ_GHJ_PWR_VR
J 0
(1650 3250);
DISPLAY 1.361702 (1650 3250);
PAINT ORANGE (1650 3250);
DISPLAY INVISIBLE (1650 3250);
FORCEPROP 1 LASTPIN (1600 3200) $PN 1
J 0
(1610 3180);
DISPLAY 0.787234 (1610 3180);
PAINT ORANGE (1610 3180);
DISPLAY INVISIBLE (1610 3180);
FORCEPROP 2 LAST CDS_SEC 1
J 0
(1650 3300);
DISPLAY 1.021277 (1650 3300);
PAINT ORANGE (1650 3300);
DISPLAY INVISIBLE (1650 3300);
FORCEPROP 2 LAST $SEC 1
J 0
(1650 3300);
DISPLAY 0.680851 (1650 3300);
PAINT MONO (1650 3300);
DISPLAY INVISIBLE (1650 3300);
FORCEADD GND..1
(1600 2900);
FORCEPROP 3 LASTPIN (1600 2950) SIG_NAME GND\g
J 0
(1610 2960);
DISPLAY 0.659574 (1610 2960);
PAINT MONO (1610 2960);
DISPLAY INVISIBLE (1610 2960);
FORCEPROP 2 LAST ROOM VDDQ_GHJ_PWR_VR
J 0
(1025 2975);
DISPLAY 1.361702 (1025 2975);
PAINT ORANGE (1025 2975);
DISPLAY INVISIBLE (1025 2975);
FORCEPROP 1 LAST VOLTAGE 0
J 0
(1600 2900);
PAINT SKYBLUE (1600 2900);
DISPLAY INVISIBLE (1600 2900);
FORCEPROP 2 LAST CDS_LIB mstr_symbols
J 0
(1600 2900);
PAINT ORANGE (1600 2900);
DISPLAY INVISIBLE (1600 2900);
FORCEPROP 1 LAST BODY_TYPE PLUMBING
J 0
(1555 2857);
DISPLAY 0.340426 (1555 2857);
PAINT GREEN (1555 2857);
DISPLAY INVISIBLE (1555 2857);
FORCEPROP 1 LAST SIZE 1B
J 0
(1675 2850);
DISPLAY 1.170213 (1675 2850);
PAINT AQUA (1675 2850);
DISPLAY INVISIBLE (1675 2850);
FORCEPROP 1 LAST PATH I26
J 0
(1675 2900);
DISPLAY 0.872340 (1675 2900);
PAINT AQUA (1675 2900);
DISPLAY INVISIBLE (1675 2900);
FORCEPROP 1 LAST HDL_POWER GND
J 0
(1600 3050);
DISPLAY 1.170213 (1600 3050);
PAINT GREEN (1600 3050);
DISPLAY INVISIBLE (1600 3050);
FORCEADD CAP_A..1
(1200 3100);
FORCEPROP 1 LASTPIN (1200 3000) $PN 2
J 0
(1210 2980);
DISPLAY 0.617021 (1210 2980);
PAINT ORANGE (1210 2980);
FORCEPROP 1 LAST MATERIAL X7R
J 0
(1250 3000);
DISPLAY 0.617021 (1250 3000);
PAINT SKYBLUE (1250 3000);
FORCEPROP 1 LAST PACK_TYPE 0402V
J 0
(1250 2900);
DISPLAY 0.617021 (1250 2900);
PAINT SKYBLUE (1250 2900);
FORCEPROP 1 LAST PART_NUMBER A36096-030
J 0
(1250 2950);
DISPLAY 0.617021 (1250 2950);
PAINT BLUE (1250 2950);
FORCEPROP 1 LAST TOLERANCE 10%
J 0
(1250 3050);
DISPLAY 0.617021 (1250 3050);
PAINT SKYBLUE (1250 3050);
FORCEPROP 1 LASTPIN (1200 3200) $PN 1
J 0
(1210 3180);
DISPLAY 0.617021 (1210 3180);
PAINT ORANGE (1210 3180);
FORCEPROP 1 LAST VOLTAGE 16V
J 0
(1250 3100);
DISPLAY 0.617021 (1250 3100);
PAINT SKYBLUE (1250 3100);
FORCEPROP 1 LAST VALUE 0.1UF
J 0
(1250 3150);
DISPLAY 0.617021 (1250 3150);
PAINT SKYBLUE (1250 3150);
FORCEPROP 1 LAST LOCATION C1G25
J 0
(1250 3200);
DISPLAY 0.617021 (1250 3200);
PAINT AQUA (1250 3200);
FORCEPROP 2 LAST CDS_LIB dev_discrete
J 0
(1200 3100);
PAINT ORANGE (1200 3100);
DISPLAY INVISIBLE (1200 3100);
FORCEPROP 2 LAST CDS_LOCATION C1G25
J 0
(1250 3200);
DISPLAY 0.617021 (1250 3200);
PAINT AQUA (1250 3200);
DISPLAY INVISIBLE (1250 3200);
FORCEPROP 1 LAST PATH I27
J 0
(1250 3250);
DISPLAY 0.978723 (1250 3250);
PAINT WHITE (1250 3250);
DISPLAY INVISIBLE (1250 3250);
FORCEPROP 2 LAST ROOM VDDQ_GHJ_PWR_VR
J 0
(1250 3250);
DISPLAY 1.361702 (1250 3250);
PAINT ORANGE (1250 3250);
DISPLAY INVISIBLE (1250 3250);
FORCEPROP 2 LAST CDS_SEC 1
J 0
(1250 3250);
PAINT ORANGE (1250 3250);
DISPLAY INVISIBLE (1250 3250);
FORCEPROP 2 LAST SEC 1
J 0
(1250 3325);
DISPLAY 0.680851 (1250 3325);
PAINT MONO (1250 3325);
DISPLAY INVISIBLE (1250 3325);
FORCEPROP 2 LAST SEC_TYPE 0402V
J 0
(1250 3325);
DISPLAY 1.021277 (1250 3325);
PAINT ORANGE (1250 3325);
DISPLAY INVISIBLE (1250 3325);
FORCEADD GND..1
(1200 2900);
FORCEPROP 3 LASTPIN (1200 2950) SIG_NAME GND\g
J 0
(1210 2960);
DISPLAY 0.659574 (1210 2960);
PAINT MONO (1210 2960);
DISPLAY INVISIBLE (1210 2960);
FORCEPROP 2 LAST ROOM VDDQ_GHJ_PWR_VR
J 0
(625 2975);
DISPLAY 1.361702 (625 2975);
PAINT ORANGE (625 2975);
DISPLAY INVISIBLE (625 2975);
FORCEPROP 1 LAST PATH I28
J 0
(1275 2900);
DISPLAY 0.872340 (1275 2900);
PAINT AQUA (1275 2900);
DISPLAY INVISIBLE (1275 2900);
FORCEPROP 1 LAST BODY_TYPE PLUMBING
J 0
(1155 2857);
DISPLAY 0.340426 (1155 2857);
PAINT GREEN (1155 2857);
DISPLAY INVISIBLE (1155 2857);
FORCEPROP 2 LAST CDS_LIB mstr_symbols
J 0
(1200 2900);
PAINT ORANGE (1200 2900);
DISPLAY INVISIBLE (1200 2900);
FORCEPROP 1 LAST SIZE 1B
J 0
(1275 2850);
DISPLAY 1.170213 (1275 2850);
PAINT AQUA (1275 2850);
DISPLAY INVISIBLE (1275 2850);
FORCEPROP 1 LAST VOLTAGE 0
J 0
(1200 2900);
PAINT SKYBLUE (1200 2900);
DISPLAY INVISIBLE (1200 2900);
FORCEPROP 1 LAST HDL_POWER GND
J 0
(1200 3050);
DISPLAY 1.170213 (1200 3050);
PAINT GREEN (1200 3050);
DISPLAY INVISIBLE (1200 3050);
FORCEADD P3V3_STBY..1
(900 3775);
FORCEPROP 3 LASTPIN (900 3725) SIG_NAME P3V3_STBY\g
J 0
(910 3735);
DISPLAY 0.659574 (910 3735);
PAINT MONO (910 3735);
DISPLAY INVISIBLE (910 3735);
FORCEPROP 1 LAST HDL_POWER P3V3_STBY
J 0
(600 3650);
DISPLAY 0.872340 (600 3650);
PAINT ORANGE (600 3650);
DISPLAY INVISIBLE (600 3650);
FORCEPROP 1 LAST VOLTAGE 3.3V
J 0
(855 3732);
DISPLAY 0.340426 (855 3732);
PAINT SKYBLUE (855 3732);
DISPLAY INVISIBLE (855 3732);
FORCEPROP 1 LAST BODY_TYPE PLUMBING
J 0
(855 3732);
DISPLAY 0.340426 (855 3732);
PAINT GREEN (855 3732);
DISPLAY INVISIBLE (855 3732);
FORCEPROP 1 LAST PATH I29
J 0
(945 3777);
DISPLAY 0.340426 (945 3777);
PAINT GREEN (945 3777);
DISPLAY INVISIBLE (945 3777);
FORCEPROP 2 LAST CDS_LIB mstr_symbols
J 0
(900 3775);
PAINT ORANGE (900 3775);
DISPLAY INVISIBLE (900 3775);
FORCEPROP 1 LAST SIZE 1B
J 0
(945 3797);
DISPLAY 0.340426 (945 3797);
PAINT GREEN (945 3797);
DISPLAY INVISIBLE (945 3797);
FORCEADD RES..2
(900 3450);
FORCEPROP 1 LAST TOLERANCE 5%
J 0
(945 3475);
DISPLAY 0.617021 (945 3475);
PAINT SKYBLUE (945 3475);
FORCEPROP 1 LASTPIN (900 3350) $PN 2
J 0
(905 3360);
DISPLAY 0.617021 (905 3360);
PAINT ORANGE (905 3360);
FORCEPROP 1 LASTPIN (900 3550) $PN 1
J 0
(905 3512);
DISPLAY 0.617021 (905 3512);
PAINT ORANGE (905 3512);
FORCEPROP 1 LAST WATTAGE 1/16W
J 0
(940 3425);
DISPLAY 0.617021 (940 3425);
PAINT SKYBLUE (940 3425);
FORCEPROP 1 LAST MATERIAL CHIP
J 0
(940 3375);
DISPLAY 0.617021 (940 3375);
PAINT SKYBLUE (940 3375);
FORCEPROP 1 LAST PACK_TYPE 0402
J 0
(940 3275);
DISPLAY 0.617021 (940 3275);
PAINT SKYBLUE (940 3275);
FORCEPROP 1 LAST VALUE 0.0
J 0
(945 3525);
DISPLAY 0.617021 (945 3525);
PAINT SKYBLUE (945 3525);
FORCEPROP 1 LAST PART_NUMBER G21497-005
J 0
(940 3325);
DISPLAY 0.617021 (940 3325);
PAINT BLUE (940 3325);
FORCEPROP 1 LAST LOCATION R9U10
J 0
(945 3575);
DISPLAY 0.617021 (945 3575);
PAINT AQUA (945 3575);
FORCEPROP 2 LAST CDS_LIB mstr_discrete
J 0
(900 3450);
PAINT ORANGE (900 3450);
DISPLAY INVISIBLE (900 3450);
FORCEPROP 2 LAST CDS_LOCATION R9U10
J 0
(945 3575);
DISPLAY 0.617021 (945 3575);
PAINT AQUA (945 3575);
DISPLAY INVISIBLE (945 3575);
FORCEPROP 2 LAST ROOM VDDQ_GHJ_PWR_VR
J 0
(950 3625);
DISPLAY 1.361702 (950 3625);
PAINT ORANGE (950 3625);
DISPLAY INVISIBLE (950 3625);
FORCEPROP 1 LAST PATH I30
J 0
(950 3625);
DISPLAY 0.978723 (950 3625);
PAINT WHITE (950 3625);
DISPLAY INVISIBLE (950 3625);
FORCEPROP 2 LAST SEC 1
J 0
(950 3700);
DISPLAY 0.680851 (950 3700);
PAINT MONO (950 3700);
DISPLAY INVISIBLE (950 3700);
FORCEPROP 2 LAST SEC_TYPE 0402
J 0
(950 3700);
DISPLAY 1.021277 (950 3700);
PAINT ORANGE (950 3700);
DISPLAY INVISIBLE (950 3700);
FORCEADD RES..1
(-1725 1075);
FORCEPROP 1 LAST WATTAGE 1/16W
J 2
(-1725 925);
DISPLAY 0.617021 (-1725 925);
PAINT SKYBLUE (-1725 925);
FORCEPROP 1 LAST MATERIAL CHIP
J 0
(-1700 925);
DISPLAY 0.617021 (-1700 925);
PAINT SKYBLUE (-1700 925);
FORCEPROP 1 LAST PACK_TYPE 0402
J 0
(-1700 975);
DISPLAY 0.617021 (-1700 975);
PAINT SKYBLUE (-1700 975);
FORCEPROP 1 LAST TOLERANCE 1%
J 0
(-1800 975);
DISPLAY 0.617021 (-1800 975);
PAINT SKYBLUE (-1800 975);
FORCEPROP 1 LAST VALUE 10.0
J 2
(-1825 975);
DISPLAY 0.617021 (-1825 975);
PAINT SKYBLUE (-1825 975);
FORCEPROP 1 LASTPIN (-1825 1075) $PN 1
J 0
(-1813 1087);
DISPLAY 0.617021 (-1813 1087);
PAINT ORANGE (-1813 1087);
FORCEPROP 1 LAST PART_NUMBER G21796-066
J 0
(-1875 1025);
DISPLAY 0.617021 (-1875 1025);
PAINT BLUE (-1875 1025);
FORCEPROP 1 LAST LOCATION R1G5
J 0
(-1775 1125);
DISPLAY 0.617021 (-1775 1125);
PAINT AQUA (-1775 1125);
FORCEPROP 1 LASTPIN (-1625 1075) $PN 2
J 0
(-1663 1087);
DISPLAY 0.617021 (-1663 1087);
PAINT ORANGE (-1663 1087);
FORCEPROP 2 LAST CDS_LIB mstr_discrete
J 0
(-1725 1075);
PAINT ORANGE (-1725 1075);
DISPLAY INVISIBLE (-1725 1075);
FORCEPROP 2 LAST CDS_LOCATION R1G5
J 0
(-1775 1125);
DISPLAY 0.617021 (-1775 1125);
PAINT AQUA (-1775 1125);
DISPLAY INVISIBLE (-1775 1125);
FORCEPROP 1 LAST PATH I32
J 0
(-1775 1225);
DISPLAY 0.978723 (-1775 1225);
PAINT WHITE (-1775 1225);
DISPLAY INVISIBLE (-1775 1225);
FORCEPROP 2 LAST ROOM VDDQ_GHJ_PWR_VR
J 0
(-1650 1175);
DISPLAY 1.361702 (-1650 1175);
PAINT ORANGE (-1650 1175);
DISPLAY INVISIBLE (-1650 1175);
FORCEPROP 2 LAST NO_XNET_CONNECTION 1
J 0
(-1775 1275);
PAINT MONO (-1775 1275);
DISPLAY INVISIBLE (-1775 1275);
FORCEPROP 2 LAST SEC_TYPE 0402
J 0
(-1775 1300);
DISPLAY 1.021277 (-1775 1300);
PAINT ORANGE (-1775 1300);
DISPLAY INVISIBLE (-1775 1300);
FORCEPROP 2 LAST SEC 1
J 0
(-1775 1300);
DISPLAY 0.680851 (-1775 1300);
PAINT MONO (-1775 1300);
DISPLAY INVISIBLE (-1775 1300);
FORCEADD OFFPAGE..1
(-2300 1075);
FORCEPROP 2 LAST $XR0 225 
J 0
(-2552 1075);
DISPLAY 0.638298 (-2552 1075);
PAINT MONO (-2552 1075);
FORCEPROP 1 LAST COMMENT_BODY TRUE
J 0
(-2175 975);
DISPLAY 1.170213 (-2175 975);
PAINT GREEN (-2175 975);
DISPLAY INVISIBLE (-2175 975);
FORCEPROP 2 LAST PATH I34
J 0
(-2575 1125);
DISPLAY 1.021277 (-2575 1125);
PAINT ORANGE (-2575 1125);
DISPLAY INVISIBLE (-2575 1125);
FORCEPROP 2 LAST ROOM VDDQ_GHJ_PWR_VR
J 0
(-2850 1150);
DISPLAY 1.361702 (-2850 1150);
PAINT ORANGE (-2850 1150);
DISPLAY INVISIBLE (-2850 1150);
FORCEPROP 2 LAST CDS_LIB mstr_standard
J 0
(-2300 1075);
PAINT ORANGE (-2300 1075);
DISPLAY INVISIBLE (-2300 1075);
FORCEPROP 1 LAST OFFPAGE TRUE
J 0
(-1975 950);
DISPLAY 1.170213 (-1975 950);
PAINT GREEN (-1975 950);
DISPLAY INVISIBLE (-1975 950);
FORCEADD GND..1
(175 850);
FORCEPROP 3 LASTPIN (175 900) SIG_NAME GND\g
J 0
(185 910);
DISPLAY 0.659574 (185 910);
PAINT MONO (185 910);
DISPLAY INVISIBLE (185 910);
FORCEPROP 2 LAST ROOM VDDQ_GHJ_PWR_VR
J 0
(-400 925);
DISPLAY 1.361702 (-400 925);
PAINT ORANGE (-400 925);
DISPLAY INVISIBLE (-400 925);
FORCEPROP 1 LAST PATH I35
J 0
(250 850);
DISPLAY 0.872340 (250 850);
PAINT AQUA (250 850);
DISPLAY INVISIBLE (250 850);
FORCEPROP 1 LAST BODY_TYPE PLUMBING
J 0
(130 807);
DISPLAY 0.340426 (130 807);
PAINT GREEN (130 807);
DISPLAY INVISIBLE (130 807);
FORCEPROP 1 LAST VOLTAGE 0
J 0
(175 850);
PAINT SKYBLUE (175 850);
DISPLAY INVISIBLE (175 850);
FORCEPROP 2 LAST CDS_LIB mstr_symbols
J 0
(175 850);
PAINT ORANGE (175 850);
DISPLAY INVISIBLE (175 850);
FORCEPROP 1 LAST SIZE 1B
J 0
(250 800);
DISPLAY 1.170213 (250 800);
PAINT AQUA (250 800);
DISPLAY INVISIBLE (250 800);
FORCEPROP 1 LAST HDL_POWER GND
J 0
(175 1000);
DISPLAY 1.170213 (175 1000);
PAINT GREEN (175 1000);
DISPLAY INVISIBLE (175 1000);
FORCEADD CAP..1
R 2
(100 750);
FORCEPROP 1 LAST MATERIAL X7R
J 2
(-75 750);
DISPLAY 0.617021 (-75 750);
PAINT SKYBLUE (-75 750);
FORCEPROP 1 LAST TOLERANCE 10%
J 2
(-125 800);
DISPLAY 0.617021 (-125 800);
PAINT SKYBLUE (-125 800);
FORCEPROP 1 LAST VOLTAGE 50V
J 2
(50 750);
DISPLAY 0.617021 (50 750);
PAINT SKYBLUE (50 750);
FORCEPROP 1 LAST PACK_TYPE 0402LF
J 2
(50 650);
DISPLAY 0.617021 (50 650);
PAINT SKYBLUE (50 650);
FORCEPROP 1 LAST VALUE 220PF
J 2
(50 800);
DISPLAY 0.617021 (50 800);
PAINT SKYBLUE (50 800);
FORCEPROP 1 LAST PART_NUMBER A36096-050
J 2
(50 700);
DISPLAY 0.617021 (50 700);
PAINT BLUE (50 700);
FORCEPROP 1 LAST LOCATION C1G24
J 2
(50 850);
DISPLAY 0.617021 (50 850);
PAINT AQUA (50 850);
FORCEPROP 1 LASTPIN (100 650) $PN 2
J 2
(90 630);
DISPLAY 0.617021 (90 630);
PAINT ORANGE (90 630);
FORCEPROP 1 LASTPIN (100 850) $PN 1
J 2
(90 830);
DISPLAY 0.617021 (90 830);
PAINT ORANGE (90 830);
FORCEPROP 2 LAST CDS_LIB mstr_discrete
J 2
(100 750);
PAINT ORANGE (100 750);
DISPLAY INVISIBLE (100 750);
FORCEPROP 2 LAST SEC_TYPE 0402LF
J 2
(50 975);
DISPLAY 1.021277 (50 975);
PAINT ORANGE (50 975);
DISPLAY INVISIBLE (50 975);
FORCEPROP 2 LAST ROOM VDDQ_GHJ_PWR_VR
J 2
(50 900);
DISPLAY 1.361702 (50 900);
PAINT ORANGE (50 900);
DISPLAY INVISIBLE (50 900);
FORCEPROP 1 LAST PATH I36
J 2
(50 900);
DISPLAY 0.978723 (50 900);
PAINT WHITE (50 900);
DISPLAY INVISIBLE (50 900);
FORCEPROP 2 LAST SEC 1
J 2
(50 975);
DISPLAY 0.680851 (50 975);
PAINT MONO (50 975);
DISPLAY INVISIBLE (50 975);
FORCEPROP 2 LAST CDS_LOCATION C1G24
J 2
(50 850);
DISPLAY 0.617021 (50 850);
PAINT AQUA (50 850);
DISPLAY INVISIBLE (50 850);
FORCEADD CAP..1
(-1450 925);
FORCEPROP 1 LASTPIN (-1450 825) $PN 2
J 0
(-1440 805);
DISPLAY 0.617021 (-1440 805);
PAINT ORANGE (-1440 805);
FORCEPROP 1 LAST VOLTAGE 50V
J 0
(-1400 925);
DISPLAY 0.617021 (-1400 925);
PAINT SKYBLUE (-1400 925);
FORCEPROP 1 LAST PART_NUMBER A36096-050
J 0
(-1400 875);
DISPLAY 0.617021 (-1400 875);
PAINT BLUE (-1400 875);
FORCEPROP 1 LAST VALUE 220PF
J 0
(-1400 975);
DISPLAY 0.617021 (-1400 975);
PAINT SKYBLUE (-1400 975);
FORCEPROP 1 LAST PACK_TYPE 0402LF
J 0
(-1400 825);
DISPLAY 0.617021 (-1400 825);
PAINT SKYBLUE (-1400 825);
FORCEPROP 1 LAST TOLERANCE 10%
J 0
(-1225 975);
DISPLAY 0.617021 (-1225 975);
PAINT SKYBLUE (-1225 975);
FORCEPROP 1 LAST MATERIAL X7R
J 0
(-1275 925);
DISPLAY 0.617021 (-1275 925);
PAINT SKYBLUE (-1275 925);
FORCEPROP 1 LASTPIN (-1450 1025) $PN 1
J 0
(-1440 1005);
DISPLAY 0.617021 (-1440 1005);
PAINT ORANGE (-1440 1005);
FORCEPROP 1 LAST LOCATION C1G16
J 0
(-1400 1025);
DISPLAY 0.617021 (-1400 1025);
PAINT AQUA (-1400 1025);
FORCEPROP 2 LAST CDS_LIB mstr_discrete
J 0
(-1450 925);
PAINT ORANGE (-1450 925);
DISPLAY INVISIBLE (-1450 925);
FORCEPROP 1 LAST PATH I39
J 0
(-1400 1075);
DISPLAY 0.978723 (-1400 1075);
PAINT WHITE (-1400 1075);
DISPLAY INVISIBLE (-1400 1075);
FORCEPROP 2 LAST NO_XNET_CONNECTION 1
J 0
(-1400 1125);
PAINT MONO (-1400 1125);
DISPLAY INVISIBLE (-1400 1125);
FORCEPROP 2 LAST ROOM VDDQ_GHJ_PWR_VR
J 0
(-1400 1075);
DISPLAY 1.361702 (-1400 1075);
PAINT ORANGE (-1400 1075);
DISPLAY INVISIBLE (-1400 1075);
FORCEPROP 2 LAST SEC_TYPE 0402LF
J 0
(-1400 1150);
DISPLAY 1.021277 (-1400 1150);
PAINT ORANGE (-1400 1150);
DISPLAY INVISIBLE (-1400 1150);
FORCEPROP 2 LAST CDS_LOCATION C1G16
J 0
(-1400 1025);
DISPLAY 0.617021 (-1400 1025);
PAINT AQUA (-1400 1025);
DISPLAY INVISIBLE (-1400 1025);
FORCEPROP 2 LAST SEC 1
J 0
(-1400 1150);
DISPLAY 0.680851 (-1400 1150);
PAINT MONO (-1400 1150);
DISPLAY INVISIBLE (-1400 1150);
FORCEADD OFFPAGE..2
(4125 1450);
FORCEPROP 2 LAST $XR0 224 
J 0
(4314 1450);
DISPLAY 0.638298 (4314 1450);
PAINT MONO (4314 1450);
FORCEPROP 1 LAST COMMENT_BODY TRUE
J 0
(4080 1355);
DISPLAY 1.170213 (4080 1355);
PAINT GREEN (4080 1355);
DISPLAY INVISIBLE (4080 1355);
FORCEPROP 2 LAST ROOM VDDQ_GHJ_PWR_VR
J 0
(3700 1525);
DISPLAY 1.361702 (3700 1525);
PAINT ORANGE (3700 1525);
DISPLAY INVISIBLE (3700 1525);
FORCEPROP 2 LAST CDS_LIB mstr_standard
J 0
(4125 1450);
PAINT ORANGE (4125 1450);
DISPLAY INVISIBLE (4125 1450);
FORCEPROP 1 LAST OFFPAGE TRUE
J 0
(4450 1325);
DISPLAY 1.170213 (4450 1325);
PAINT GREEN (4450 1325);
DISPLAY INVISIBLE (4450 1325);
FORCEPROP 2 LAST PATH I4
J 0
(4300 1525);
DISPLAY 1.021277 (4300 1525);
PAINT ORANGE (4300 1525);
DISPLAY INVISIBLE (4300 1525);
FORCEADD OFFPAGE..1
R 2
(4425 300);
FORCEPROP 2 LAST $XR0 223 
J 0
(4611 300);
DISPLAY 0.638298 (4611 300);
PAINT MONO (4611 300);
FORCEPROP 2 LAST ROOM VDDQ_GHJ_PWR_VR
J 0
(4000 375);
DISPLAY 1.361702 (4000 375);
PAINT ORANGE (4000 375);
DISPLAY INVISIBLE (4000 375);
FORCEPROP 1 LAST COMMENT_BODY TRUE
J 2
(4300 200);
DISPLAY 1.170213 (4300 200);
PAINT GREEN (4300 200);
DISPLAY INVISIBLE (4300 200);
FORCEPROP 1 LAST OFFPAGE TRUE
J 2
(4100 175);
DISPLAY 1.170213 (4100 175);
PAINT GREEN (4100 175);
DISPLAY INVISIBLE (4100 175);
FORCEPROP 2 LAST CDS_LIB mstr_standard
J 2
(4425 300);
PAINT ORANGE (4425 300);
DISPLAY INVISIBLE (4425 300);
FORCEPROP 2 LAST PATH I40
J 0
(4625 350);
DISPLAY 1.021277 (4625 350);
PAINT ORANGE (4625 350);
DISPLAY INVISIBLE (4625 350);
FORCEADD CAP_A..1
(3775 125);
FORCEPROP 1 LAST PACK_TYPE 0402V
J 0
(3825 -75);
DISPLAY 0.617021 (3825 -75);
PAINT SKYBLUE (3825 -75);
FORCEPROP 1 LAST PART_NUMBER D97712-004
J 0
(3825 -25);
DISPLAY 0.617021 (3825 -25);
PAINT BLUE (3825 -25);
FORCEPROP 1 LAST MATERIAL X6S
J 0
(3825 25);
DISPLAY 0.617021 (3825 25);
PAINT SKYBLUE (3825 25);
FORCEPROP 1 LAST VOLTAGE 6.3V
J 0
(3825 125);
DISPLAY 0.617021 (3825 125);
PAINT SKYBLUE (3825 125);
FORCEPROP 1 LAST TOLERANCE 10%
J 0
(3825 75);
DISPLAY 0.617021 (3825 75);
PAINT SKYBLUE (3825 75);
FORCEPROP 1 LAST VALUE 1.0UF
J 0
(3825 175);
DISPLAY 0.617021 (3825 175);
PAINT SKYBLUE (3825 175);
FORCEPROP 1 LAST LOCATION C1G23
J 0
(3825 225);
DISPLAY 0.617021 (3825 225);
PAINT AQUA (3825 225);
FORCEPROP 2 LAST CDS_LOCATION C1G23
J 0
(3825 225);
DISPLAY 0.617021 (3825 225);
PAINT AQUA (3825 225);
DISPLAY INVISIBLE (3825 225);
FORCEPROP 2 LAST CDS_LIB dev_discrete
J 0
(3775 125);
PAINT ORANGE (3775 125);
DISPLAY INVISIBLE (3775 125);
FORCEPROP 1 LASTPIN (3775 225) $PN 1
J 0
(3785 205);
DISPLAY 0.787234 (3785 205);
PAINT ORANGE (3785 205);
DISPLAY INVISIBLE (3785 205);
FORCEPROP 1 LASTPIN (3775 25) $PN 2
J 0
(3785 5);
DISPLAY 0.787234 (3785 5);
PAINT ORANGE (3785 5);
DISPLAY INVISIBLE (3785 5);
FORCEPROP 2 LAST CDS_SEC 1
J 0
(3825 325);
DISPLAY 1.021277 (3825 325);
PAINT ORANGE (3825 325);
DISPLAY INVISIBLE (3825 325);
FORCEPROP 2 LAST $SEC 1
J 0
(3825 325);
DISPLAY 0.680851 (3825 325);
PAINT MONO (3825 325);
DISPLAY INVISIBLE (3825 325);
FORCEPROP 1 LAST PATH I41
J 0
(3825 275);
DISPLAY 0.978723 (3825 275);
PAINT WHITE (3825 275);
DISPLAY INVISIBLE (3825 275);
FORCEPROP 2 LAST ROOM VDDQ_GHJ_PWR_VR
J 0
(3825 275);
DISPLAY 1.361702 (3825 275);
PAINT ORANGE (3825 275);
DISPLAY INVISIBLE (3825 275);
FORCEADD GND..1
(3775 -175);
FORCEPROP 3 LASTPIN (3775 -125) SIG_NAME GND\g
J 0
(3785 -115);
DISPLAY 0.659574 (3785 -115);
PAINT MONO (3785 -115);
DISPLAY INVISIBLE (3785 -115);
FORCEPROP 2 LAST ROOM VDDQ_GHJ_PWR_VR
J 0
(3200 -100);
DISPLAY 1.361702 (3200 -100);
PAINT ORANGE (3200 -100);
DISPLAY INVISIBLE (3200 -100);
FORCEPROP 1 LAST PATH I42
J 0
(3850 -175);
DISPLAY 0.872340 (3850 -175);
PAINT AQUA (3850 -175);
DISPLAY INVISIBLE (3850 -175);
FORCEPROP 1 LAST BODY_TYPE PLUMBING
J 0
(3730 -218);
DISPLAY 0.340426 (3730 -218);
PAINT GREEN (3730 -218);
DISPLAY INVISIBLE (3730 -218);
FORCEPROP 2 LAST CDS_LIB mstr_symbols
J 0
(3775 -175);
PAINT ORANGE (3775 -175);
DISPLAY INVISIBLE (3775 -175);
FORCEPROP 1 LAST SIZE 1B
J 0
(3850 -225);
DISPLAY 1.170213 (3850 -225);
PAINT AQUA (3850 -225);
DISPLAY INVISIBLE (3850 -225);
FORCEPROP 1 LAST VOLTAGE 0
J 0
(3775 -175);
PAINT SKYBLUE (3775 -175);
DISPLAY INVISIBLE (3775 -175);
FORCEPROP 1 LAST HDL_POWER GND
J 0
(3775 -25);
DISPLAY 1.170213 (3775 -25);
PAINT GREEN (3775 -25);
DISPLAY INVISIBLE (3775 -25);
FORCEADD GND..1
(3375 -75);
FORCEPROP 3 LASTPIN (3375 -25) SIG_NAME GND\g
J 0
(3385 -15);
DISPLAY 0.659574 (3385 -15);
PAINT MONO (3385 -15);
DISPLAY INVISIBLE (3385 -15);
FORCEPROP 1 LAST PATH I43
J 0
(3450 -75);
DISPLAY 0.872340 (3450 -75);
PAINT AQUA (3450 -75);
DISPLAY INVISIBLE (3450 -75);
FORCEPROP 1 LAST VOLTAGE 0
J 0
(3375 -75);
PAINT SKYBLUE (3375 -75);
DISPLAY INVISIBLE (3375 -75);
FORCEPROP 1 LAST SIZE 1B
J 0
(3450 -125);
DISPLAY 1.170213 (3450 -125);
PAINT AQUA (3450 -125);
DISPLAY INVISIBLE (3450 -125);
FORCEPROP 2 LAST CDS_LIB mstr_symbols
J 0
(3375 -75);
PAINT ORANGE (3375 -75);
DISPLAY INVISIBLE (3375 -75);
FORCEPROP 1 LAST BODY_TYPE PLUMBING
J 0
(3330 -118);
DISPLAY 0.340426 (3330 -118);
PAINT GREEN (3330 -118);
DISPLAY INVISIBLE (3330 -118);
FORCEPROP 2 LAST ROOM VDDQ_GHJ_PWR_VR
J 0
(2800 0);
DISPLAY 1.361702 (2800 0);
PAINT ORANGE (2800 0);
DISPLAY INVISIBLE (2800 0);
FORCEPROP 1 LAST HDL_POWER GND
J 0
(3375 75);
DISPLAY 1.170213 (3375 75);
PAINT GREEN (3375 75);
DISPLAY INVISIBLE (3375 75);
FORCEADD CAP_A..1
(3375 125);
FORCEPROP 1 LAST PACK_TYPE 0402V
J 0
(3425 -75);
DISPLAY 0.617021 (3425 -75);
PAINT SKYBLUE (3425 -75);
FORCEPROP 1 LAST PART_NUMBER A36096-030
J 0
(3425 -25);
DISPLAY 0.617021 (3425 -25);
PAINT BLUE (3425 -25);
FORCEPROP 1 LASTPIN (3375 25) $PN 2
J 0
(3385 5);
DISPLAY 0.617021 (3385 5);
PAINT ORANGE (3385 5);
FORCEPROP 1 LASTPIN (3375 225) $PN 1
J 0
(3385 205);
DISPLAY 0.617021 (3385 205);
PAINT ORANGE (3385 205);
FORCEPROP 1 LAST TOLERANCE 10%
J 0
(3425 75);
DISPLAY 0.617021 (3425 75);
PAINT SKYBLUE (3425 75);
FORCEPROP 1 LAST VALUE 0.1UF
J 0
(3425 175);
DISPLAY 0.617021 (3425 175);
PAINT SKYBLUE (3425 175);
FORCEPROP 1 LAST LOCATION C1G22
J 0
(3425 225);
DISPLAY 0.617021 (3425 225);
PAINT AQUA (3425 225);
FORCEPROP 1 LAST VOLTAGE 16V
J 0
(3425 125);
DISPLAY 0.617021 (3425 125);
PAINT SKYBLUE (3425 125);
FORCEPROP 1 LAST MATERIAL X7R
J 0
(3425 25);
DISPLAY 0.617021 (3425 25);
PAINT SKYBLUE (3425 25);
FORCEPROP 2 LAST CDS_LOCATION C1G22
J 0
(3425 225);
DISPLAY 0.617021 (3425 225);
PAINT AQUA (3425 225);
DISPLAY INVISIBLE (3425 225);
FORCEPROP 2 LAST CDS_LIB dev_discrete
J 0
(3375 125);
PAINT ORANGE (3375 125);
DISPLAY INVISIBLE (3375 125);
FORCEPROP 1 LAST PATH I44
J 0
(3425 275);
DISPLAY 0.978723 (3425 275);
PAINT WHITE (3425 275);
DISPLAY INVISIBLE (3425 275);
FORCEPROP 2 LAST SEC_TYPE 0402V
J 0
(3425 350);
DISPLAY 1.021277 (3425 350);
PAINT ORANGE (3425 350);
DISPLAY INVISIBLE (3425 350);
FORCEPROP 2 LAST CDS_SEC 1
J 0
(3425 275);
PAINT ORANGE (3425 275);
DISPLAY INVISIBLE (3425 275);
FORCEPROP 2 LAST ROOM VDDQ_GHJ_PWR_VR
J 0
(3425 275);
DISPLAY 1.361702 (3425 275);
PAINT ORANGE (3425 275);
DISPLAY INVISIBLE (3425 275);
FORCEPROP 2 LAST SEC 1
J 0
(3425 350);
DISPLAY 0.680851 (3425 350);
PAINT MONO (3425 350);
DISPLAY INVISIBLE (3425 350);
FORCEADD OFFPAGE..1
(-2275 800);
FORCEPROP 2 LAST $XR0 225 
J 0
(-2527 800);
DISPLAY 0.638298 (-2527 800);
PAINT MONO (-2527 800);
FORCEPROP 2 LAST ROOM VDDQ_GHJ_PWR_VR
J 0
(-2825 875);
DISPLAY 1.361702 (-2825 875);
PAINT ORANGE (-2825 875);
DISPLAY INVISIBLE (-2825 875);
FORCEPROP 2 LAST PATH I45
J 0
(-2550 850);
DISPLAY 1.021277 (-2550 850);
PAINT ORANGE (-2550 850);
DISPLAY INVISIBLE (-2550 850);
FORCEPROP 1 LAST COMMENT_BODY TRUE
J 0
(-2150 700);
DISPLAY 1.170213 (-2150 700);
PAINT GREEN (-2150 700);
DISPLAY INVISIBLE (-2150 700);
FORCEPROP 2 LAST CDS_LIB mstr_standard
J 0
(-2275 800);
PAINT ORANGE (-2275 800);
DISPLAY INVISIBLE (-2275 800);
FORCEPROP 1 LAST OFFPAGE TRUE
J 0
(-1950 675);
DISPLAY 1.170213 (-1950 675);
PAINT GREEN (-1950 675);
DISPLAY INVISIBLE (-1950 675);
FORCEADD GND..1
(625 50);
FORCEPROP 3 LASTPIN (625 100) SIG_NAME GND\g
J 0
(635 110);
DISPLAY 0.659574 (635 110);
PAINT MONO (635 110);
DISPLAY INVISIBLE (635 110);
FORCEPROP 1 LAST SIZE 1B
J 0
(700 0);
DISPLAY 1.170213 (700 0);
PAINT AQUA (700 0);
DISPLAY INVISIBLE (700 0);
FORCEPROP 2 LAST ROOM VDDQ_GHJ_PWR_VR
J 0
(50 125);
DISPLAY 1.361702 (50 125);
PAINT ORANGE (50 125);
DISPLAY INVISIBLE (50 125);
FORCEPROP 1 LAST VOLTAGE 0
J 0
(625 50);
PAINT SKYBLUE (625 50);
DISPLAY INVISIBLE (625 50);
FORCEPROP 2 LAST CDS_LIB mstr_symbols
J 0
(625 50);
PAINT ORANGE (625 50);
DISPLAY INVISIBLE (625 50);
FORCEPROP 1 LAST BODY_TYPE PLUMBING
J 0
(580 7);
DISPLAY 0.340426 (580 7);
PAINT GREEN (580 7);
DISPLAY INVISIBLE (580 7);
FORCEPROP 1 LAST HDL_POWER GND
J 0
(625 200);
DISPLAY 1.170213 (625 200);
PAINT GREEN (625 200);
DISPLAY INVISIBLE (625 200);
FORCEPROP 1 LAST PATH I46
J 0
(700 50);
DISPLAY 0.872340 (700 50);
PAINT AQUA (700 50);
DISPLAY INVISIBLE (700 50);
FORCEADD GND..1
(275 50);
FORCEPROP 3 LASTPIN (275 100) SIG_NAME GND\g
J 0
(285 110);
DISPLAY 0.659574 (285 110);
PAINT MONO (285 110);
DISPLAY INVISIBLE (285 110);
FORCEPROP 2 LAST ROOM VDDQ_GHJ_PWR_VR
J 0
(-300 125);
DISPLAY 1.361702 (-300 125);
PAINT ORANGE (-300 125);
DISPLAY INVISIBLE (-300 125);
FORCEPROP 1 LAST SIZE 1B
J 0
(350 0);
DISPLAY 1.170213 (350 0);
PAINT AQUA (350 0);
DISPLAY INVISIBLE (350 0);
FORCEPROP 1 LAST BODY_TYPE PLUMBING
J 0
(230 7);
DISPLAY 0.340426 (230 7);
PAINT GREEN (230 7);
DISPLAY INVISIBLE (230 7);
FORCEPROP 1 LAST VOLTAGE 0
J 0
(275 50);
PAINT SKYBLUE (275 50);
DISPLAY INVISIBLE (275 50);
FORCEPROP 2 LAST CDS_LIB mstr_symbols
J 0
(275 50);
PAINT ORANGE (275 50);
DISPLAY INVISIBLE (275 50);
FORCEPROP 1 LAST PATH I47
J 0
(350 50);
DISPLAY 0.872340 (350 50);
PAINT AQUA (350 50);
DISPLAY INVISIBLE (350 50);
FORCEPROP 1 LAST HDL_POWER GND
J 0
(275 200);
DISPLAY 1.170213 (275 200);
PAINT GREEN (275 200);
DISPLAY INVISIBLE (275 200);
FORCEADD GND..1
(100 50);
FORCEPROP 3 LASTPIN (100 100) SIG_NAME GND\g
J 0
(110 110);
DISPLAY 0.659574 (110 110);
PAINT MONO (110 110);
DISPLAY INVISIBLE (110 110);
FORCEPROP 2 LAST ROOM VDDQ_GHJ_PWR_VR
J 0
(-475 125);
DISPLAY 1.361702 (-475 125);
PAINT ORANGE (-475 125);
DISPLAY INVISIBLE (-475 125);
FORCEPROP 1 LAST SIZE 1B
J 0
(175 0);
DISPLAY 1.170213 (175 0);
PAINT AQUA (175 0);
DISPLAY INVISIBLE (175 0);
FORCEPROP 1 LAST HDL_POWER GND
J 0
(100 200);
DISPLAY 1.170213 (100 200);
PAINT GREEN (100 200);
DISPLAY INVISIBLE (100 200);
FORCEPROP 1 LAST PATH I48
J 0
(175 50);
DISPLAY 0.872340 (175 50);
PAINT AQUA (175 50);
DISPLAY INVISIBLE (175 50);
FORCEPROP 1 LAST BODY_TYPE PLUMBING
J 0
(55 7);
DISPLAY 0.340426 (55 7);
PAINT GREEN (55 7);
DISPLAY INVISIBLE (55 7);
FORCEPROP 2 LAST CDS_LIB mstr_symbols
J 0
(100 50);
PAINT ORANGE (100 50);
DISPLAY INVISIBLE (100 50);
FORCEPROP 1 LAST VOLTAGE 0
J 0
(100 50);
PAINT SKYBLUE (100 50);
DISPLAY INVISIBLE (100 50);
FORCEADD PVCCIO_CPU1..1
(-625 3925);
FORCEPROP 3 LASTPIN (-625 3875) SIG_NAME PVCCIO_CPU1\g
J 0
(-615 3885);
DISPLAY 0.659574 (-615 3885);
PAINT MONO (-615 3885);
DISPLAY INVISIBLE (-615 3885);
FORCEPROP 1 LAST HDL_POWER PVCCIO_CPU1
J 1
(-625 3975);
DISPLAY 0.872340 (-625 3975);
PAINT GREEN (-625 3975);
DISPLAY INVISIBLE (-625 3975);
FORCEPROP 1 LAST PATH I49
J 0
(-575 3950);
DISPLAY 0.872340 (-575 3950);
PAINT AQUA (-575 3950);
DISPLAY INVISIBLE (-575 3950);
FORCEPROP 1 LAST BODY_TYPE PLUMBING
J 0
(-670 3882);
DISPLAY 0.340426 (-670 3882);
PAINT GREEN (-670 3882);
DISPLAY INVISIBLE (-670 3882);
FORCEPROP 2 LAST CDS_LIB mstr_symbols
J 0
(-625 3925);
PAINT ORANGE (-625 3925);
DISPLAY INVISIBLE (-625 3925);
FORCEPROP 1 LAST VOLTAGE 1.1V
J 0
(-670 3882);
DISPLAY 0.340426 (-670 3882);
PAINT SKYBLUE (-670 3882);
DISPLAY INVISIBLE (-670 3882);
FORCEADD RES..2
(-625 3350);
FORCEPROP 1 LASTPIN (-625 3250) $PN 2
J 0
(-620 3260);
DISPLAY 0.617021 (-620 3260);
PAINT ORANGE (-620 3260);
FORCEPROP 1 LASTPIN (-625 3450) $PN 1
J 0
(-620 3412);
DISPLAY 0.617021 (-620 3412);
PAINT ORANGE (-620 3412);
FORCEPROP 1 LAST TOLERANCE 1%
J 0
(-580 3375);
DISPLAY 0.617021 (-580 3375);
PAINT SKYBLUE (-580 3375);
FORCEPROP 1 LAST WATTAGE 1/16W
J 0
(-585 3325);
DISPLAY 0.617021 (-585 3325);
PAINT SKYBLUE (-585 3325);
FORCEPROP 1 LAST PACK_TYPE 0402
J 0
(-585 3175);
DISPLAY 0.617021 (-585 3175);
PAINT SKYBLUE (-585 3175);
FORCEPROP 1 LAST VALUE 49.9
J 0
(-580 3425);
DISPLAY 0.617021 (-580 3425);
PAINT SKYBLUE (-580 3425);
FORCEPROP 1 LAST PART_NUMBER G21796-047
J 0
(-585 3225);
DISPLAY 0.617021 (-585 3225);
PAINT BLUE (-585 3225);
FORCEPROP 1 LAST LOCATION R9U4
J 0
(-580 3475);
DISPLAY 0.617021 (-580 3475);
PAINT AQUA (-580 3475);
FORCEPROP 1 LAST MATERIAL EMPTY
J 0
(-585 3275);
DISPLAY 0.617021 (-585 3275);
PAINT RED (-585 3275);
FORCEPROP 2 LAST CDS_LIB mstr_discrete
J 0
(-625 3350);
PAINT ORANGE (-625 3350);
DISPLAY INVISIBLE (-625 3350);
FORCEPROP 2 LAST ROOM VDDQ_GHJ_PWR_VR
J 0
(-575 3525);
DISPLAY 1.361702 (-575 3525);
PAINT ORANGE (-575 3525);
DISPLAY INVISIBLE (-575 3525);
FORCEPROP 1 LAST PATH I50
J 0
(-575 3525);
DISPLAY 0.978723 (-575 3525);
PAINT WHITE (-575 3525);
DISPLAY INVISIBLE (-575 3525);
FORCEPROP 2 LAST CDS_LOCATION R9U4
J 0
(-580 3475);
DISPLAY 0.617021 (-580 3475);
PAINT AQUA (-580 3475);
DISPLAY INVISIBLE (-580 3475);
FORCEPROP 2 LAST SEC 1
J 0
(-575 3600);
PAINT MONO (-575 3600);
DISPLAY INVISIBLE (-575 3600);
FORCEPROP 2 LAST SEC_TYPE 0402
J 0
(-575 3600);
DISPLAY 1.021277 (-575 3600);
PAINT ORANGE (-575 3600);
DISPLAY INVISIBLE (-575 3600);
FORCEADD RES..1
(-225 2975);
FORCEPROP 1 LASTPIN (-325 2975) $PN 1
J 0
(-313 2987);
DISPLAY 0.617021 (-313 2987);
PAINT ORANGE (-313 2987);
FORCEPROP 1 LAST WATTAGE 1/16W
J 2
(-175 3000);
DISPLAY 0.617021 (-175 3000);
PAINT SKYBLUE (-175 3000);
FORCEPROP 1 LASTPIN (-125 2975) $PN 2
J 0
(-163 2987);
DISPLAY 0.617021 (-163 2987);
PAINT ORANGE (-163 2987);
FORCEPROP 1 LAST MATERIAL CHIP
J 0
(-125 3000);
DISPLAY 0.617021 (-125 3000);
PAINT SKYBLUE (-125 3000);
FORCEPROP 1 LAST TOLERANCE 1%
J 0
(-175 3050);
DISPLAY 0.617021 (-175 3050);
PAINT SKYBLUE (-175 3050);
FORCEPROP 1 LAST VALUE 150.0
J 2
(-225 3050);
DISPLAY 0.617021 (-225 3050);
PAINT SKYBLUE (-225 3050);
FORCEPROP 1 LAST PART_NUMBER G21796-009
J 0
(-325 3100);
DISPLAY 0.617021 (-325 3100);
PAINT BLUE (-325 3100);
FORCEPROP 1 LAST LOCATION R1G7
J 0
(-325 3150);
DISPLAY 0.617021 (-325 3150);
PAINT AQUA (-325 3150);
FORCEPROP 1 LAST PACK_TYPE 0402
J 0
(-50 3050);
DISPLAY 0.617021 (-50 3050);
PAINT SKYBLUE (-50 3050);
FORCEPROP 2 LAST CDS_LIB mstr_discrete
J 0
(-225 2975);
PAINT ORANGE (-225 2975);
DISPLAY INVISIBLE (-225 2975);
FORCEPROP 2 LAST ROOM VDDQ_GHJ_PWR_VR
J 0
(-325 3200);
DISPLAY 1.361702 (-325 3200);
PAINT ORANGE (-325 3200);
DISPLAY INVISIBLE (-325 3200);
FORCEPROP 1 LAST PATH I53
J 0
(-275 3125);
DISPLAY 0.978723 (-275 3125);
PAINT WHITE (-275 3125);
DISPLAY INVISIBLE (-275 3125);
FORCEPROP 2 LAST CDS_LOCATION R1G7
J 0
(-325 3150);
DISPLAY 0.617021 (-325 3150);
PAINT AQUA (-325 3150);
DISPLAY INVISIBLE (-325 3150);
FORCEPROP 2 LAST SEC 1
J 0
(-275 3200);
DISPLAY 0.680851 (-275 3200);
PAINT MONO (-275 3200);
DISPLAY INVISIBLE (-275 3200);
FORCEPROP 2 LAST SEC_TYPE 0402
J 0
(-275 3200);
DISPLAY 1.021277 (-275 3200);
PAINT ORANGE (-275 3200);
DISPLAY INVISIBLE (-275 3200);
FORCEADD VCC_CORE..1
(-1175 3925);
FORCEPROP 3 LASTPIN (-1175 3875) SIG_NAME VR_FET_SW_P12V_STBY_PVDDQ_GHJ\g
J 0
(-1165 3885);
DISPLAY 0.659574 (-1165 3885);
PAINT MONO (-1165 3885);
DISPLAY INVISIBLE (-1165 3885);
FORCEPROP 1 LAST HDL_POWER VR_FET_SW_P12V_STBY_PVDDQ_GHJ
J 1
(-1450 3975);
DISPLAY 0.617021 (-1450 3975);
PAINT GREEN (-1450 3975);
FORCEPROP 1 LAST PATH I56
J 0
(-1125 3950);
DISPLAY 0.872340 (-1125 3950);
PAINT AQUA (-1125 3950);
DISPLAY INVISIBLE (-1125 3950);
FORCEPROP 2 LAST CDS_LIB mstr_symbols
J 0
(-1175 3925);
PAINT ORANGE (-1175 3925);
DISPLAY INVISIBLE (-1175 3925);
FORCEADD RES..2
(-1175 3700);
FORCEPROP 1 LASTPIN (-1175 3600) $PN 2
J 0
(-1170 3610);
DISPLAY 0.617021 (-1170 3610);
PAINT ORANGE (-1170 3610);
FORCEPROP 1 LASTPIN (-1175 3800) $PN 1
J 0
(-1170 3762);
DISPLAY 0.617021 (-1170 3762);
PAINT ORANGE (-1170 3762);
FORCEPROP 1 LAST WATTAGE 1/16W
J 0
(-1135 3675);
DISPLAY 0.617021 (-1135 3675);
PAINT SKYBLUE (-1135 3675);
FORCEPROP 1 LAST MATERIAL CHIP
J 0
(-1135 3625);
DISPLAY 0.617021 (-1135 3625);
PAINT SKYBLUE (-1135 3625);
FORCEPROP 1 LAST PACK_TYPE 0402
J 0
(-1135 3525);
DISPLAY 0.617021 (-1135 3525);
PAINT SKYBLUE (-1135 3525);
FORCEPROP 1 LAST PART_NUMBER G21796-160
J 0
(-1135 3575);
DISPLAY 0.617021 (-1135 3575);
PAINT BLUE (-1135 3575);
FORCEPROP 1 LAST TOLERANCE 1%
J 0
(-1130 3725);
DISPLAY 0.617021 (-1130 3725);
PAINT SKYBLUE (-1130 3725);
FORCEPROP 1 LAST VALUE 100.0K
J 0
(-1130 3775);
DISPLAY 0.617021 (-1130 3775);
PAINT SKYBLUE (-1130 3775);
FORCEPROP 1 LAST LOCATION R9U11
J 0
(-1130 3825);
DISPLAY 0.617021 (-1130 3825);
PAINT AQUA (-1130 3825);
FORCEPROP 2 LAST CDS_LIB mstr_discrete
J 0
(-1175 3700);
PAINT ORANGE (-1175 3700);
DISPLAY INVISIBLE (-1175 3700);
FORCEPROP 2 LAST CDS_LOCATION R9U11
J 0
(-1130 3825);
DISPLAY 0.617021 (-1130 3825);
PAINT AQUA (-1130 3825);
DISPLAY INVISIBLE (-1130 3825);
FORCEPROP 2 LAST ROOM VDDQ_GHJ_PWR_VR
J 0
(-1125 3875);
DISPLAY 1.361702 (-1125 3875);
PAINT ORANGE (-1125 3875);
DISPLAY INVISIBLE (-1125 3875);
FORCEPROP 1 LAST PATH I57
J 0
(-1125 3875);
DISPLAY 0.978723 (-1125 3875);
PAINT WHITE (-1125 3875);
DISPLAY INVISIBLE (-1125 3875);
FORCEPROP 2 LAST SEC 1
J 0
(-1125 3925);
DISPLAY 0.680851 (-1125 3925);
PAINT MONO (-1125 3925);
DISPLAY INVISIBLE (-1125 3925);
FORCEPROP 2 LAST SEC_TYPE 0402
J 0
(-1125 3925);
DISPLAY 1.021277 (-1125 3925);
PAINT ORANGE (-1125 3925);
DISPLAY INVISIBLE (-1125 3925);
FORCEADD RES..2
(-1175 3350);
FORCEPROP 1 LASTPIN (-1175 3250) $PN 2
J 0
(-1170 3260);
DISPLAY 0.617021 (-1170 3260);
PAINT ORANGE (-1170 3260);
FORCEPROP 1 LASTPIN (-1175 3450) $PN 1
J 0
(-1170 3412);
DISPLAY 0.617021 (-1170 3412);
PAINT ORANGE (-1170 3412);
FORCEPROP 1 LAST TOLERANCE 1%
J 0
(-1130 3375);
DISPLAY 0.617021 (-1130 3375);
PAINT SKYBLUE (-1130 3375);
FORCEPROP 1 LAST WATTAGE 1/16W
J 0
(-1135 3325);
DISPLAY 0.617021 (-1135 3325);
PAINT SKYBLUE (-1135 3325);
FORCEPROP 1 LAST MATERIAL CHIP
J 0
(-1135 3275);
DISPLAY 0.617021 (-1135 3275);
PAINT SKYBLUE (-1135 3275);
FORCEPROP 1 LAST PACK_TYPE 0402
J 0
(-1135 3175);
DISPLAY 0.617021 (-1135 3175);
PAINT SKYBLUE (-1135 3175);
FORCEPROP 1 LAST VALUE 1.5K
J 0
(-1130 3425);
DISPLAY 0.617021 (-1130 3425);
PAINT SKYBLUE (-1130 3425);
FORCEPROP 1 LAST PART_NUMBER G21796-003
J 0
(-1135 3225);
DISPLAY 0.617021 (-1135 3225);
PAINT BLUE (-1135 3225);
FORCEPROP 1 LAST LOCATION R1G24
J 0
(-1130 3475);
DISPLAY 0.617021 (-1130 3475);
PAINT AQUA (-1130 3475);
FORCEPROP 2 LAST CDS_LIB mstr_discrete
J 0
(-1175 3350);
PAINT ORANGE (-1175 3350);
DISPLAY INVISIBLE (-1175 3350);
FORCEPROP 2 LAST CDS_LOCATION R1G24
J 0
(-1130 3475);
DISPLAY 0.617021 (-1130 3475);
PAINT AQUA (-1130 3475);
DISPLAY INVISIBLE (-1130 3475);
FORCEPROP 1 LAST PATH I58
J 0
(-1125 3525);
DISPLAY 0.978723 (-1125 3525);
PAINT WHITE (-1125 3525);
DISPLAY INVISIBLE (-1125 3525);
FORCEPROP 2 LAST ROOM VDDQ_GHJ_PWR_VR
J 0
(-1125 3525);
DISPLAY 1.361702 (-1125 3525);
PAINT ORANGE (-1125 3525);
DISPLAY INVISIBLE (-1125 3525);
FORCEPROP 2 LAST SEC 1
J 0
(-1125 3575);
DISPLAY 0.680851 (-1125 3575);
PAINT MONO (-1125 3575);
DISPLAY INVISIBLE (-1125 3575);
FORCEPROP 2 LAST SEC_TYPE 0402
J 0
(-1125 3575);
DISPLAY 1.021277 (-1125 3575);
PAINT ORANGE (-1125 3575);
DISPLAY INVISIBLE (-1125 3575);
FORCEADD CAP..1
R 2
(-1400 3350);
FORCEPROP 1 LAST MATERIAL X7R
J 2
(-1450 3250);
DISPLAY 0.617021 (-1450 3250);
PAINT SKYBLUE (-1450 3250);
FORCEPROP 1 LAST VOLTAGE 50V
J 2
(-1450 3350);
DISPLAY 0.617021 (-1450 3350);
PAINT SKYBLUE (-1450 3350);
FORCEPROP 1 LAST PACK_TYPE 0402LF
J 2
(-1450 3150);
DISPLAY 0.617021 (-1450 3150);
PAINT SKYBLUE (-1450 3150);
FORCEPROP 1 LAST TOLERANCE 10%
J 2
(-1450 3300);
DISPLAY 0.617021 (-1450 3300);
PAINT SKYBLUE (-1450 3300);
FORCEPROP 1 LAST VALUE 1000PF
J 2
(-1450 3400);
DISPLAY 0.617021 (-1450 3400);
PAINT SKYBLUE (-1450 3400);
FORCEPROP 1 LAST PART_NUMBER A36096-046
J 2
(-1450 3200);
DISPLAY 0.617021 (-1450 3200);
PAINT BLUE (-1450 3200);
FORCEPROP 1 LAST LOCATION C1G26
J 2
(-1450 3450);
DISPLAY 0.617021 (-1450 3450);
PAINT AQUA (-1450 3450);
FORCEPROP 1 LASTPIN (-1400 3250) $PN 2
J 2
(-1410 3230);
DISPLAY 0.617021 (-1410 3230);
PAINT ORANGE (-1410 3230);
FORCEPROP 1 LASTPIN (-1400 3450) $PN 1
J 2
(-1410 3430);
DISPLAY 0.617021 (-1410 3430);
PAINT ORANGE (-1410 3430);
FORCEPROP 2 LAST CDS_LOCATION C1G26
J 2
(-1450 3450);
DISPLAY 0.617021 (-1450 3450);
PAINT AQUA (-1450 3450);
DISPLAY INVISIBLE (-1450 3450);
FORCEPROP 1 LAST PATH I59
J 2
(-1450 3500);
DISPLAY 0.978723 (-1450 3500);
PAINT WHITE (-1450 3500);
DISPLAY INVISIBLE (-1450 3500);
FORCEPROP 2 LAST ROOM VDDQ_GHJ_PWR_VR
J 0
(-1450 3500);
DISPLAY 1.361702 (-1450 3500);
PAINT ORANGE (-1450 3500);
DISPLAY INVISIBLE (-1450 3500);
FORCEPROP 2 LAST CDS_LIB mstr_discrete
J 2
(-1400 3350);
PAINT ORANGE (-1400 3350);
DISPLAY INVISIBLE (-1400 3350);
FORCEPROP 2 LAST SEC 1
J 0
(-1450 3575);
DISPLAY 0.680851 (-1450 3575);
PAINT MONO (-1450 3575);
DISPLAY INVISIBLE (-1450 3575);
FORCEPROP 2 LAST SEC_TYPE 0402LF
J 0
(-1450 3575);
DISPLAY 1.021277 (-1450 3575);
PAINT ORANGE (-1450 3575);
DISPLAY INVISIBLE (-1450 3575);
FORCEADD GND..1
(-1175 3125);
FORCEPROP 3 LASTPIN (-1175 3175) SIG_NAME GND\g
J 0
(-1165 3185);
DISPLAY 0.659574 (-1165 3185);
PAINT MONO (-1165 3185);
DISPLAY INVISIBLE (-1165 3185);
FORCEPROP 2 LAST ROOM VDDQ_GHJ_PWR_VR
J 0
(-1750 3200);
DISPLAY 1.361702 (-1750 3200);
PAINT ORANGE (-1750 3200);
DISPLAY INVISIBLE (-1750 3200);
FORCEPROP 1 LAST BODY_TYPE PLUMBING
J 0
(-1220 3082);
DISPLAY 0.340426 (-1220 3082);
PAINT GREEN (-1220 3082);
DISPLAY INVISIBLE (-1220 3082);
FORCEPROP 2 LAST CDS_LIB mstr_symbols
J 0
(-1175 3125);
PAINT ORANGE (-1175 3125);
DISPLAY INVISIBLE (-1175 3125);
FORCEPROP 1 LAST VOLTAGE 0
J 0
(-1175 3125);
PAINT SKYBLUE (-1175 3125);
DISPLAY INVISIBLE (-1175 3125);
FORCEPROP 1 LAST HDL_POWER GND
J 0
(-1175 3275);
DISPLAY 1.170213 (-1175 3275);
PAINT GREEN (-1175 3275);
DISPLAY INVISIBLE (-1175 3275);
FORCEPROP 1 LAST SIZE 1B
J 0
(-1100 3075);
DISPLAY 1.170213 (-1100 3075);
PAINT AQUA (-1100 3075);
DISPLAY INVISIBLE (-1100 3075);
FORCEPROP 1 LAST PATH I60
J 0
(-1100 3125);
DISPLAY 0.872340 (-1100 3125);
PAINT AQUA (-1100 3125);
DISPLAY INVISIBLE (-1100 3125);
FORCEADD GND..1
(-1400 3125);
FORCEPROP 3 LASTPIN (-1400 3175) SIG_NAME GND\g
J 0
(-1390 3185);
DISPLAY 0.659574 (-1390 3185);
PAINT MONO (-1390 3185);
DISPLAY INVISIBLE (-1390 3185);
FORCEPROP 2 LAST ROOM VDDQ_GHJ_PWR_VR
J 0
(-1975 3200);
DISPLAY 1.361702 (-1975 3200);
PAINT ORANGE (-1975 3200);
DISPLAY INVISIBLE (-1975 3200);
FORCEPROP 1 LAST BODY_TYPE PLUMBING
J 0
(-1445 3082);
DISPLAY 0.340426 (-1445 3082);
PAINT GREEN (-1445 3082);
DISPLAY INVISIBLE (-1445 3082);
FORCEPROP 1 LAST VOLTAGE 0
J 0
(-1400 3125);
PAINT SKYBLUE (-1400 3125);
DISPLAY INVISIBLE (-1400 3125);
FORCEPROP 2 LAST CDS_LIB mstr_symbols
J 0
(-1400 3125);
PAINT ORANGE (-1400 3125);
DISPLAY INVISIBLE (-1400 3125);
FORCEPROP 1 LAST SIZE 1B
J 0
(-1325 3075);
DISPLAY 1.170213 (-1325 3075);
PAINT AQUA (-1325 3075);
DISPLAY INVISIBLE (-1325 3075);
FORCEPROP 1 LAST PATH I61
J 0
(-1325 3125);
DISPLAY 0.872340 (-1325 3125);
PAINT AQUA (-1325 3125);
DISPLAY INVISIBLE (-1325 3125);
FORCEPROP 1 LAST HDL_POWER GND
J 0
(-1400 3275);
DISPLAY 1.170213 (-1400 3275);
PAINT GREEN (-1400 3275);
DISPLAY INVISIBLE (-1400 3275);
FORCEADD OFFPAGE..2
R 2
(-2175 3550);
FORCEPROP 2 LAST $XR0 223 
J 0
(-2430 3550);
DISPLAY 0.638298 (-2430 3550);
PAINT MONO (-2430 3550);
FORCEPROP 2 LAST ROOM VDDQ_GHJ_PWR_VR
J 0
(-2725 3625);
DISPLAY 1.361702 (-2725 3625);
PAINT ORANGE (-2725 3625);
DISPLAY INVISIBLE (-2725 3625);
FORCEPROP 1 LAST OFFPAGE TRUE
J 2
(-2500 3425);
DISPLAY 1.170213 (-2500 3425);
PAINT GREEN (-2500 3425);
DISPLAY INVISIBLE (-2500 3425);
FORCEPROP 1 LAST COMMENT_BODY TRUE
J 2
(-2130 3455);
DISPLAY 1.170213 (-2130 3455);
PAINT GREEN (-2130 3455);
DISPLAY INVISIBLE (-2130 3455);
FORCEPROP 2 LAST CDS_LIB mstr_standard
J 2
(-2175 3550);
PAINT ORANGE (-2175 3550);
DISPLAY INVISIBLE (-2175 3550);
FORCEPROP 2 LAST PATH I62
J 0
(-2450 3600);
DISPLAY 1.021277 (-2450 3600);
PAINT ORANGE (-2450 3600);
DISPLAY INVISIBLE (-2450 3600);
FORCEADD OFFPAGE..1
(-2200 2975);
FORCEPROP 2 LAST $XR0 55 
J 0
(-2451 2975);
DISPLAY 0.638298 (-2451 2975);
PAINT MONO (-2451 2975);
FORCEPROP 2 LAST $XR1 193 
J 0
(-2571 2975);
DISPLAY 0.638298 (-2571 2975);
PAINT MONO (-2571 2975);
FORCEPROP 2 LAST $XR2 226 
J 0
(-2691 2975);
DISPLAY 0.638298 (-2691 2975);
PAINT MONO (-2691 2975);
FORCEPROP 2 LAST PATH I63
J 0
(-2375 3025);
DISPLAY 1.021277 (-2375 3025);
PAINT ORANGE (-2375 3025);
DISPLAY INVISIBLE (-2375 3025);
FORCEPROP 1 LAST COMMENT_BODY TRUE
J 0
(-2075 2875);
DISPLAY 1.170213 (-2075 2875);
PAINT GREEN (-2075 2875);
DISPLAY INVISIBLE (-2075 2875);
FORCEPROP 2 LAST CDS_LIB mstr_standard
J 0
(-2200 2975);
PAINT ORANGE (-2200 2975);
DISPLAY INVISIBLE (-2200 2975);
FORCEPROP 2 LAST ROOM VDDQ_GHJ_PWR_VR
J 0
(-2750 3050);
DISPLAY 1.361702 (-2750 3050);
PAINT ORANGE (-2750 3050);
DISPLAY INVISIBLE (-2750 3050);
FORCEPROP 1 LAST OFFPAGE TRUE
J 0
(-1875 2850);
DISPLAY 1.170213 (-1875 2850);
PAINT GREEN (-1875 2850);
DISPLAY INVISIBLE (-1875 2850);
FORCEADD OFFPAGE..1
(-2175 2350);
FORCEPROP 2 LAST $XR0 224 
J 0
(-2427 2350);
DISPLAY 0.638298 (-2427 2350);
PAINT MONO (-2427 2350);
FORCEPROP 2 LAST ROOM VDDQ_GHJ_PWR_VR
J 0
(-2725 2425);
DISPLAY 1.361702 (-2725 2425);
PAINT ORANGE (-2725 2425);
DISPLAY INVISIBLE (-2725 2425);
FORCEPROP 1 LAST COMMENT_BODY TRUE
J 0
(-2050 2250);
DISPLAY 1.170213 (-2050 2250);
PAINT GREEN (-2050 2250);
DISPLAY INVISIBLE (-2050 2250);
FORCEPROP 2 LAST PATH I64
J 0
(-2125 2425);
DISPLAY 1.021277 (-2125 2425);
PAINT ORANGE (-2125 2425);
DISPLAY INVISIBLE (-2125 2425);
FORCEPROP 2 LAST CDS_LIB mstr_standard
J 0
(-2175 2350);
PAINT ORANGE (-2175 2350);
DISPLAY INVISIBLE (-2175 2350);
FORCEPROP 1 LAST OFFPAGE TRUE
J 0
(-1850 2225);
DISPLAY 1.170213 (-1850 2225);
PAINT GREEN (-1850 2225);
DISPLAY INVISIBLE (-1850 2225);
FORCEADD OFFPAGE..1
(-2175 2300);
FORCEPROP 2 LAST $XR0 224 
J 0
(-2427 2300);
DISPLAY 0.638298 (-2427 2300);
PAINT MONO (-2427 2300);
FORCEPROP 2 LAST ROOM VDDQ_GHJ_PWR_VR
J 0
(-2725 2375);
DISPLAY 1.361702 (-2725 2375);
PAINT ORANGE (-2725 2375);
DISPLAY INVISIBLE (-2725 2375);
FORCEPROP 1 LAST COMMENT_BODY TRUE
J 0
(-2050 2200);
DISPLAY 1.170213 (-2050 2200);
PAINT GREEN (-2050 2200);
DISPLAY INVISIBLE (-2050 2200);
FORCEPROP 2 LAST CDS_LIB mstr_standard
J 0
(-2175 2300);
PAINT ORANGE (-2175 2300);
DISPLAY INVISIBLE (-2175 2300);
FORCEPROP 2 LAST PATH I65
J 0
(-2125 2375);
DISPLAY 1.021277 (-2125 2375);
PAINT ORANGE (-2125 2375);
DISPLAY INVISIBLE (-2125 2375);
FORCEPROP 1 LAST OFFPAGE TRUE
J 0
(-1850 2175);
DISPLAY 1.170213 (-1850 2175);
PAINT GREEN (-1850 2175);
DISPLAY INVISIBLE (-1850 2175);
FORCEADD OFFPAGE..1
(-2175 2150);
FORCEPROP 2 LAST $XR0 224 
J 0
(-2427 2150);
DISPLAY 0.638298 (-2427 2150);
PAINT MONO (-2427 2150);
FORCEPROP 2 LAST ROOM VDDQ_GHJ_PWR_VR
J 0
(-2725 2225);
DISPLAY 1.361702 (-2725 2225);
PAINT ORANGE (-2725 2225);
DISPLAY INVISIBLE (-2725 2225);
FORCEPROP 1 LAST COMMENT_BODY TRUE
J 0
(-2050 2050);
DISPLAY 1.170213 (-2050 2050);
PAINT GREEN (-2050 2050);
DISPLAY INVISIBLE (-2050 2050);
FORCEPROP 2 LAST CDS_LIB mstr_standard
J 0
(-2175 2150);
PAINT ORANGE (-2175 2150);
DISPLAY INVISIBLE (-2175 2150);
FORCEPROP 2 LAST PATH I67
J 0
(-2125 2225);
DISPLAY 1.021277 (-2125 2225);
PAINT ORANGE (-2125 2225);
DISPLAY INVISIBLE (-2125 2225);
FORCEPROP 1 LAST OFFPAGE TRUE
J 0
(-1850 2025);
DISPLAY 1.170213 (-1850 2025);
PAINT GREEN (-1850 2025);
DISPLAY INVISIBLE (-1850 2025);
FORCEADD OFFPAGE..1
(-2175 2100);
FORCEPROP 2 LAST $XR0 224 
J 0
(-2427 2100);
DISPLAY 0.638298 (-2427 2100);
PAINT MONO (-2427 2100);
FORCEPROP 1 LAST COMMENT_BODY TRUE
J 0
(-2050 2000);
DISPLAY 1.170213 (-2050 2000);
PAINT GREEN (-2050 2000);
DISPLAY INVISIBLE (-2050 2000);
FORCEPROP 2 LAST ROOM VDDQ_GHJ_PWR_VR
J 0
(-2725 2175);
DISPLAY 1.361702 (-2725 2175);
PAINT ORANGE (-2725 2175);
DISPLAY INVISIBLE (-2725 2175);
FORCEPROP 2 LAST CDS_LIB mstr_standard
J 0
(-2175 2100);
PAINT ORANGE (-2175 2100);
DISPLAY INVISIBLE (-2175 2100);
FORCEPROP 2 LAST PATH I68
J 0
(-2125 2175);
DISPLAY 1.021277 (-2125 2175);
PAINT ORANGE (-2125 2175);
DISPLAY INVISIBLE (-2125 2175);
FORCEPROP 1 LAST OFFPAGE TRUE
J 0
(-1850 1975);
DISPLAY 1.170213 (-1850 1975);
PAINT GREEN (-1850 1975);
DISPLAY INVISIBLE (-1850 1975);
FORCEADD PVCCIO_CPU1..1
(3925 3000);
FORCEPROP 3 LASTPIN (3925 2950) SIG_NAME PVCCIO_CPU1\g
J 0
(3935 2960);
DISPLAY 0.659574 (3935 2960);
PAINT MONO (3935 2960);
DISPLAY INVISIBLE (3935 2960);
FORCEPROP 1 LAST VOLTAGE 1.1V
J 0
(3880 2957);
DISPLAY 0.340426 (3880 2957);
PAINT SKYBLUE (3880 2957);
DISPLAY INVISIBLE (3880 2957);
FORCEPROP 2 LAST CDS_LIB mstr_symbols
J 0
(3925 3000);
PAINT ORANGE (3925 3000);
DISPLAY INVISIBLE (3925 3000);
FORCEPROP 1 LAST BODY_TYPE PLUMBING
J 0
(3880 2957);
DISPLAY 0.340426 (3880 2957);
PAINT GREEN (3880 2957);
DISPLAY INVISIBLE (3880 2957);
FORCEPROP 1 LAST PATH I7
J 0
(3975 3025);
DISPLAY 0.872340 (3975 3025);
PAINT AQUA (3975 3025);
DISPLAY INVISIBLE (3975 3025);
FORCEPROP 1 LAST HDL_POWER PVCCIO_CPU1
J 1
(3925 3050);
DISPLAY 0.872340 (3925 3050);
PAINT GREEN (3925 3050);
DISPLAY INVISIBLE (3925 3050);
FORCEADD OFFPAGE..1
(-2175 1900);
FORCEPROP 2 LAST $XR0 197 
J 0
(-2427 1900);
DISPLAY 0.638298 (-2427 1900);
PAINT MONO (-2427 1900);
FORCEPROP 2 LAST ROOM VDDQ_GHJ_PWR_VR
J 0
(-2725 1975);
DISPLAY 1.361702 (-2725 1975);
PAINT ORANGE (-2725 1975);
DISPLAY INVISIBLE (-2725 1975);
FORCEPROP 1 LAST COMMENT_BODY TRUE
J 0
(-2050 1800);
DISPLAY 1.170213 (-2050 1800);
PAINT GREEN (-2050 1800);
DISPLAY INVISIBLE (-2050 1800);
FORCEPROP 2 LAST CDS_LIB mstr_standard
J 0
(-2175 1900);
PAINT ORANGE (-2175 1900);
DISPLAY INVISIBLE (-2175 1900);
FORCEPROP 2 LAST PATH I70
J 0
(-2125 1975);
DISPLAY 1.021277 (-2125 1975);
PAINT ORANGE (-2125 1975);
DISPLAY INVISIBLE (-2125 1975);
FORCEPROP 1 LAST OFFPAGE TRUE
J 0
(-1850 1775);
DISPLAY 1.170213 (-1850 1775);
PAINT GREEN (-1850 1775);
DISPLAY INVISIBLE (-1850 1775);
FORCEADD OFFPAGE..1
(-2175 1800);
FORCEPROP 2 LAST $XR0 224 
J 0
(-2427 1800);
DISPLAY 0.638298 (-2427 1800);
PAINT MONO (-2427 1800);
FORCEPROP 2 LAST ROOM VDDQ_GHJ_PWR_VR
J 0
(-2725 1875);
DISPLAY 1.361702 (-2725 1875);
PAINT ORANGE (-2725 1875);
DISPLAY INVISIBLE (-2725 1875);
FORCEPROP 1 LAST COMMENT_BODY TRUE
J 0
(-2050 1700);
DISPLAY 1.170213 (-2050 1700);
PAINT GREEN (-2050 1700);
DISPLAY INVISIBLE (-2050 1700);
FORCEPROP 2 LAST CDS_LIB mstr_standard
J 0
(-2175 1800);
PAINT ORANGE (-2175 1800);
DISPLAY INVISIBLE (-2175 1800);
FORCEPROP 2 LAST PATH I71
J 0
(-2125 1875);
DISPLAY 1.021277 (-2125 1875);
PAINT ORANGE (-2125 1875);
DISPLAY INVISIBLE (-2125 1875);
FORCEPROP 1 LAST OFFPAGE TRUE
J 0
(-1850 1675);
DISPLAY 1.170213 (-1850 1675);
PAINT GREEN (-1850 1675);
DISPLAY INVISIBLE (-1850 1675);
FORCEADD OFFPAGE..1
(-2175 1950);
FORCEPROP 2 LAST $XR0 223 
J 0
(-2427 1950);
DISPLAY 0.638298 (-2427 1950);
PAINT MONO (-2427 1950);
FORCEPROP 1 LAST COMMENT_BODY TRUE
J 0
(-2050 1850);
DISPLAY 1.170213 (-2050 1850);
PAINT GREEN (-2050 1850);
DISPLAY INVISIBLE (-2050 1850);
FORCEPROP 2 LAST CDS_LIB mstr_standard
J 0
(-2175 1950);
PAINT ORANGE (-2175 1950);
DISPLAY INVISIBLE (-2175 1950);
FORCEPROP 2 LAST PATH I72
J 0
(-2125 2025);
DISPLAY 1.021277 (-2125 2025);
PAINT ORANGE (-2125 2025);
DISPLAY INVISIBLE (-2125 2025);
FORCEPROP 2 LAST ROOM VDDQ_GHJ_PWR_VR
J 0
(-2725 2025);
DISPLAY 1.361702 (-2725 2025);
PAINT ORANGE (-2725 2025);
DISPLAY INVISIBLE (-2725 2025);
FORCEPROP 1 LAST OFFPAGE TRUE
J 0
(-1850 1825);
DISPLAY 1.170213 (-1850 1825);
PAINT GREEN (-1850 1825);
DISPLAY INVISIBLE (-1850 1825);
FORCEADD OFFPAGE..1
(-2175 1500);
FORCEPROP 2 LAST $XR0 191 
J 0
(-2427 1500);
DISPLAY 0.638298 (-2427 1500);
PAINT MONO (-2427 1500);
FORCEPROP 2 LAST ROOM VDDQ_GHJ_PWR_VR
J 0
(-2725 1575);
DISPLAY 1.361702 (-2725 1575);
PAINT ORANGE (-2725 1575);
DISPLAY INVISIBLE (-2725 1575);
FORCEPROP 1 LAST COMMENT_BODY TRUE
J 0
(-2050 1400);
DISPLAY 1.170213 (-2050 1400);
PAINT GREEN (-2050 1400);
DISPLAY INVISIBLE (-2050 1400);
FORCEPROP 2 LAST CDS_LIB mstr_standard
J 0
(-2175 1500);
PAINT ORANGE (-2175 1500);
DISPLAY INVISIBLE (-2175 1500);
FORCEPROP 2 LAST PATH I74
J 0
(-2125 1575);
DISPLAY 1.021277 (-2125 1575);
PAINT ORANGE (-2125 1575);
DISPLAY INVISIBLE (-2125 1575);
FORCEPROP 1 LAST OFFPAGE TRUE
J 0
(-1850 1375);
DISPLAY 1.170213 (-1850 1375);
PAINT GREEN (-1850 1375);
DISPLAY INVISIBLE (-1850 1375);
FORCEADD RES..2
(275 300);
FORCEPROP 1 LASTPIN (275 200) $PN 2
J 0
(280 210);
DISPLAY 0.617021 (280 210);
PAINT ORANGE (280 210);
FORCEPROP 1 LAST PACK_TYPE 0402
J 0
(315 125);
DISPLAY 0.617021 (315 125);
PAINT SKYBLUE (315 125);
FORCEPROP 1 LAST MATERIAL CHIP
J 0
(315 225);
DISPLAY 0.617021 (315 225);
PAINT SKYBLUE (315 225);
FORCEPROP 1 LAST TOLERANCE 1%
J 0
(320 325);
DISPLAY 0.617021 (320 325);
PAINT SKYBLUE (320 325);
FORCEPROP 1 LASTPIN (275 400) $PN 1
J 0
(280 362);
DISPLAY 0.617021 (280 362);
PAINT ORANGE (280 362);
FORCEPROP 1 LAST LOCATION R1G23
J 0
(320 425);
DISPLAY 0.617021 (320 425);
PAINT AQUA (320 425);
FORCEPROP 1 LAST VALUE 4.02K
J 0
(320 375);
DISPLAY 0.617021 (320 375);
PAINT SKYBLUE (320 375);
FORCEPROP 1 LAST WATTAGE 1/16W
J 0
(315 275);
DISPLAY 0.617021 (315 275);
PAINT SKYBLUE (315 275);
FORCEPROP 1 LAST PART_NUMBER G21796-082
J 0
(315 175);
DISPLAY 0.617021 (315 175);
PAINT BLUE (315 175);
FORCEPROP 2 LAST CDS_LIB mstr_discrete
J 0
(275 300);
PAINT ORANGE (275 300);
DISPLAY INVISIBLE (275 300);
FORCEPROP 2 LAST CDS_LOCATION R1G23
J 0
(320 425);
DISPLAY 0.617021 (320 425);
PAINT AQUA (320 425);
DISPLAY INVISIBLE (320 425);
FORCEPROP 0 LAST SEC 1
J 0
(325 475);
DISPLAY 0.680851 (325 475);
PAINT MONO (325 475);
DISPLAY INVISIBLE (325 475);
FORCEPROP 1 LAST PATH I77
J 0
(325 475);
DISPLAY 0.978723 (325 475);
PAINT WHITE (325 475);
DISPLAY INVISIBLE (325 475);
FORCEPROP 2 LAST SEC_TYPE 0402
J 0
(325 525);
DISPLAY 1.021277 (325 525);
PAINT ORANGE (325 525);
DISPLAY INVISIBLE (325 525);
FORCEPROP 0 LAST ROOM VDDQ_GHJ_PWR_VR
J 0
(325 525);
DISPLAY 1.021277 (325 525);
PAINT ORANGE (325 525);
DISPLAY INVISIBLE (325 525);
FORCEADD RES..2
(625 300);
FORCEPROP 1 LASTPIN (625 200) $PN 2
J 0
(630 210);
DISPLAY 0.617021 (630 210);
PAINT ORANGE (630 210);
FORCEPROP 1 LASTPIN (625 400) $PN 1
J 0
(630 362);
DISPLAY 0.617021 (630 362);
PAINT ORANGE (630 362);
FORCEPROP 1 LAST WATTAGE 1/16W
J 0
(665 275);
DISPLAY 0.617021 (665 275);
PAINT SKYBLUE (665 275);
FORCEPROP 1 LAST MATERIAL CHIP
J 0
(665 225);
DISPLAY 0.617021 (665 225);
PAINT SKYBLUE (665 225);
FORCEPROP 1 LAST PACK_TYPE 0402
J 0
(665 125);
DISPLAY 0.617021 (665 125);
PAINT SKYBLUE (665 125);
FORCEPROP 1 LAST TOLERANCE 1.0%
J 0
(670 325);
DISPLAY 0.617021 (670 325);
PAINT SKYBLUE (670 325);
FORCEPROP 1 LAST VALUE 5.36K
J 0
(670 375);
DISPLAY 0.617021 (670 375);
PAINT SKYBLUE (670 375);
FORCEPROP 1 LAST PART_NUMBER G21796-297
J 0
(665 175);
DISPLAY 0.617021 (665 175);
PAINT BLUE (665 175);
FORCEPROP 1 LAST LOCATION R1G22
J 0
(670 425);
DISPLAY 0.617021 (670 425);
PAINT AQUA (670 425);
FORCEPROP 2 LAST CDS_LOCATION R1G22
J 0
(670 425);
DISPLAY 0.617021 (670 425);
PAINT AQUA (670 425);
DISPLAY INVISIBLE (670 425);
FORCEPROP 0 LAST SEC 1
J 0
(675 475);
DISPLAY 0.680851 (675 475);
PAINT MONO (675 475);
DISPLAY INVISIBLE (675 475);
FORCEPROP 2 LAST CDS_LIB mstr_discrete
J 0
(625 300);
PAINT ORANGE (625 300);
DISPLAY INVISIBLE (625 300);
FORCEPROP 1 LAST PATH I78
J 0
(675 475);
DISPLAY 0.978723 (675 475);
PAINT WHITE (675 475);
DISPLAY INVISIBLE (675 475);
FORCEPROP 0 LAST ROOM VDDQ_GHJ_PWR_VR
J 0
(675 525);
DISPLAY 1.021277 (675 525);
PAINT ORANGE (675 525);
DISPLAY INVISIBLE (675 525);
FORCEPROP 2 LAST SEC_TYPE 0402
J 0
(675 525);
DISPLAY 1.021277 (675 525);
PAINT ORANGE (675 525);
DISPLAY INVISIBLE (675 525);
FORCEADD RES..2
(2200 3125);
FORCEPROP 1 LAST PART_NUMBER G21796-026
J 0
(2240 3000);
DISPLAY 0.617021 (2240 3000);
PAINT BLUE (2240 3000);
FORCEPROP 1 LAST PACK_TYPE 0402
J 0
(2240 2950);
DISPLAY 0.617021 (2240 2950);
PAINT SKYBLUE (2240 2950);
FORCEPROP 1 LASTPIN (2200 3025) $PN 2
J 0
(2205 3035);
DISPLAY 0.617021 (2205 3035);
PAINT ORANGE (2205 3035);
FORCEPROP 1 LAST MATERIAL CHIP
J 0
(2240 3050);
DISPLAY 0.617021 (2240 3050);
PAINT SKYBLUE (2240 3050);
FORCEPROP 1 LASTPIN (2200 3225) $PN 1
J 0
(2205 3187);
DISPLAY 0.617021 (2205 3187);
PAINT ORANGE (2205 3187);
FORCEPROP 1 LAST TOLERANCE 1%
J 0
(2245 3150);
DISPLAY 0.617021 (2245 3150);
PAINT SKYBLUE (2245 3150);
FORCEPROP 1 LAST WATTAGE 1/16W
J 0
(2240 3100);
DISPLAY 0.617021 (2240 3100);
PAINT SKYBLUE (2240 3100);
FORCEPROP 1 LAST VALUE 1.00K
J 0
(2245 3200);
DISPLAY 0.617021 (2245 3200);
PAINT SKYBLUE (2245 3200);
FORCEPROP 1 LAST LOCATION R1G11
J 0
(2245 3250);
DISPLAY 0.617021 (2245 3250);
PAINT AQUA (2245 3250);
FORCEPROP 2 LAST CDS_LIB mstr_discrete
J 0
(2200 3125);
PAINT ORANGE (2200 3125);
DISPLAY INVISIBLE (2200 3125);
FORCEPROP 2 LAST CDS_LOCATION R1G11
J 0
(2245 3250);
DISPLAY 0.617021 (2245 3250);
PAINT AQUA (2245 3250);
DISPLAY INVISIBLE (2245 3250);
FORCEPROP 1 LAST PATH I79
J 0
(2250 3300);
DISPLAY 0.978723 (2250 3300);
PAINT WHITE (2250 3300);
DISPLAY INVISIBLE (2250 3300);
FORCEPROP 2 LAST SEC 1
J 0
(2250 3350);
DISPLAY 0.680851 (2250 3350);
PAINT MONO (2250 3350);
DISPLAY INVISIBLE (2250 3350);
FORCEPROP 2 LAST SEC_TYPE 0402
J 0
(2250 3350);
DISPLAY 1.021277 (2250 3350);
PAINT ORANGE (2250 3350);
DISPLAY INVISIBLE (2250 3350);
FORCEPROP 0 LAST ROOM RQ_PVDDQ_GHJ_VRHOT_LVT3_N
J 0
(2250 3350);
DISPLAY 1.021277 (2250 3350);
PAINT ORANGE (2250 3350);
DISPLAY INVISIBLE (2250 3350);
FORCEADD RES..2
(3925 2800);
FORCEPROP 1 LASTPIN (3925 2700) $PN 2
J 0
(3930 2710);
DISPLAY 0.617021 (3930 2710);
PAINT ORANGE (3930 2710);
FORCEPROP 1 LAST MATERIAL CHIP
J 0
(3965 2725);
DISPLAY 0.617021 (3965 2725);
PAINT SKYBLUE (3965 2725);
FORCEPROP 1 LAST PACK_TYPE 0402
J 0
(3965 2625);
DISPLAY 0.617021 (3965 2625);
PAINT SKYBLUE (3965 2625);
FORCEPROP 1 LASTPIN (3925 2900) $PN 1
J 0
(3930 2862);
DISPLAY 0.617021 (3930 2862);
PAINT ORANGE (3930 2862);
FORCEPROP 1 LAST LOCATION R9U3
J 0
(3970 2925);
DISPLAY 0.617021 (3970 2925);
PAINT AQUA (3970 2925);
FORCEPROP 1 LAST TOLERANCE 1%
J 0
(3970 2825);
DISPLAY 0.617021 (3970 2825);
PAINT SKYBLUE (3970 2825);
FORCEPROP 1 LAST WATTAGE 1/16W
J 0
(3965 2775);
DISPLAY 0.617021 (3965 2775);
PAINT SKYBLUE (3965 2775);
FORCEPROP 1 LAST VALUE 100.0
J 0
(3970 2875);
DISPLAY 0.617021 (3970 2875);
PAINT SKYBLUE (3970 2875);
FORCEPROP 1 LAST PART_NUMBER G21796-017
J 0
(3965 2675);
DISPLAY 0.617021 (3965 2675);
PAINT BLUE (3965 2675);
FORCEPROP 2 LAST CDS_LIB mstr_discrete
J 0
(3925 2800);
PAINT ORANGE (3925 2800);
DISPLAY INVISIBLE (3925 2800);
FORCEPROP 2 LAST CDS_LOCATION R9U3
J 0
(3970 2925);
DISPLAY 0.617021 (3970 2925);
PAINT AQUA (3970 2925);
DISPLAY INVISIBLE (3970 2925);
FORCEPROP 1 LAST PATH I8
J 0
(3975 2975);
DISPLAY 0.978723 (3975 2975);
PAINT WHITE (3975 2975);
DISPLAY INVISIBLE (3975 2975);
FORCEPROP 2 LAST ROOM VDDQ_GHJ_PWR_VR
J 0
(3975 2975);
DISPLAY 1.361702 (3975 2975);
PAINT ORANGE (3975 2975);
DISPLAY INVISIBLE (3975 2975);
FORCEPROP 2 LAST SEC 1
J 0
(3975 3050);
DISPLAY 0.680851 (3975 3050);
PAINT MONO (3975 3050);
DISPLAY INVISIBLE (3975 3050);
FORCEPROP 2 LAST SEC_TYPE 0402
J 0
(3975 3050);
DISPLAY 1.021277 (3975 3050);
PAINT ORANGE (3975 3050);
DISPLAY INVISIBLE (3975 3050);
FORCEADD CAP..1
(3050 1000);
FORCEPROP 1 LASTPIN (3050 1100) $PN 1
J 0
(3060 1080);
DISPLAY 0.617021 (3060 1080);
PAINT ORANGE (3060 1080);
FORCEPROP 1 LASTPIN (3050 900) $PN 2
J 0
(3060 880);
DISPLAY 0.617021 (3060 880);
PAINT ORANGE (3060 880);
FORCEPROP 1 LAST PART_NUMBER A36096-046
J 0
(3100 850);
DISPLAY 0.617021 (3100 850);
PAINT BLUE (3100 850);
FORCEPROP 1 LAST TOLERANCE 10%
J 0
(3100 950);
DISPLAY 0.617021 (3100 950);
PAINT SKYBLUE (3100 950);
FORCEPROP 1 LAST PACK_TYPE 0402LF
J 0
(3100 800);
DISPLAY 0.617021 (3100 800);
PAINT SKYBLUE (3100 800);
FORCEPROP 1 LAST MATERIAL X7R
J 0
(3100 900);
DISPLAY 0.617021 (3100 900);
PAINT SKYBLUE (3100 900);
FORCEPROP 1 LAST VOLTAGE 50V
J 0
(3100 1000);
DISPLAY 0.617021 (3100 1000);
PAINT SKYBLUE (3100 1000);
FORCEPROP 1 LAST VALUE 1000PF
J 0
(3100 1050);
DISPLAY 0.617021 (3100 1050);
PAINT SKYBLUE (3100 1050);
FORCEPROP 1 LAST LOCATION C1G21
J 0
(3100 1100);
DISPLAY 0.617021 (3100 1100);
PAINT AQUA (3100 1100);
FORCEPROP 2 LAST CDS_LIB mstr_discrete
J 0
(3050 1000);
PAINT MONO (3050 1000);
DISPLAY INVISIBLE (3050 1000);
FORCEPROP 2 LAST SEC_TYPE 0402LF
J 0
(3100 1200);
DISPLAY 1.021277 (3100 1200);
PAINT ORANGE (3100 1200);
DISPLAY INVISIBLE (3100 1200);
FORCEPROP 2 LAST SEC 1
J 0
(3100 1200);
DISPLAY 0.680851 (3100 1200);
PAINT MONO (3100 1200);
DISPLAY INVISIBLE (3100 1200);
FORCEPROP 2 LAST CDS_LOCATION C1G21
J 0
(3100 1100);
DISPLAY 0.617021 (3100 1100);
PAINT AQUA (3100 1100);
DISPLAY INVISIBLE (3100 1100);
FORCEPROP 1 LAST PATH I80
J 0
(3100 1150);
DISPLAY 0.978723 (3100 1150);
PAINT WHITE (3100 1150);
DISPLAY INVISIBLE (3100 1150);
FORCEPROP 0 LAST ROOM VDDQ_GHJ_PWR_VR
J 0
(3100 1200);
DISPLAY 1.021277 (3100 1200);
PAINT ORANGE (3100 1200);
DISPLAY INVISIBLE (3100 1200);
FORCEADD GND..1
(3050 700);
FORCEPROP 3 LASTPIN (3050 750) SIG_NAME GND\g
J 0
(3060 760);
DISPLAY 0.659574 (3060 760);
PAINT MONO (3060 760);
DISPLAY INVISIBLE (3060 760);
FORCEPROP 2 LAST ROOM VDDQ_GHJ_PWR_VR
J 0
(2475 775);
DISPLAY 1.361702 (2475 775);
PAINT ORANGE (2475 775);
DISPLAY INVISIBLE (2475 775);
FORCEPROP 1 LAST VOLTAGE 0
J 0
(3050 700);
PAINT SKYBLUE (3050 700);
DISPLAY INVISIBLE (3050 700);
FORCEPROP 2 LAST CDS_LIB mstr_symbols
J 0
(3050 700);
PAINT MONO (3050 700);
DISPLAY INVISIBLE (3050 700);
FORCEPROP 1 LAST BODY_TYPE PLUMBING
J 0
(3005 657);
DISPLAY 0.340426 (3005 657);
PAINT GREEN (3005 657);
DISPLAY INVISIBLE (3005 657);
FORCEPROP 1 LAST HDL_POWER GND
J 0
(3050 850);
DISPLAY 1.170213 (3050 850);
PAINT GREEN (3050 850);
DISPLAY INVISIBLE (3050 850);
FORCEPROP 1 LAST SIZE 1B
J 0
(3125 650);
DISPLAY 1.170213 (3125 650);
PAINT AQUA (3125 650);
DISPLAY INVISIBLE (3125 650);
FORCEPROP 1 LAST PATH I81
J 0
(3125 700);
DISPLAY 0.872340 (3125 700);
PAINT AQUA (3125 700);
DISPLAY INVISIBLE (3125 700);
FORCEADD RES..1
(3475 2450);
FORCEPROP 1 LAST WATTAGE 1/16W
J 2
(3450 2300);
DISPLAY 0.617021 (3450 2300);
PAINT SKYBLUE (3450 2300);
FORCEPROP 1 LASTPIN (3375 2450) $PN 1
J 0
(3387 2462);
DISPLAY 0.617021 (3387 2462);
PAINT ORANGE (3387 2462);
FORCEPROP 1 LAST VALUE 33.2
J 2
(3450 2350);
DISPLAY 0.617021 (3450 2350);
PAINT SKYBLUE (3450 2350);
FORCEPROP 1 LAST LOCATION R1G8
J 0
(3425 2500);
DISPLAY 0.617021 (3425 2500);
PAINT AQUA (3425 2500);
FORCEPROP 1 LASTPIN (3575 2450) $PN 2
J 0
(3537 2462);
DISPLAY 0.617021 (3537 2462);
PAINT ORANGE (3537 2462);
FORCEPROP 1 LAST TOLERANCE 1%
J 0
(3475 2350);
DISPLAY 0.617021 (3475 2350);
PAINT SKYBLUE (3475 2350);
FORCEPROP 1 LAST MATERIAL CHIP
J 0
(3475 2300);
DISPLAY 0.617021 (3475 2300);
PAINT SKYBLUE (3475 2300);
FORCEPROP 1 LAST PART_NUMBER G21796-074
J 0
(3375 2250);
DISPLAY 0.617021 (3375 2250);
PAINT BLUE (3375 2250);
FORCEPROP 1 LAST PACK_TYPE 0402
J 0
(3725 2300);
DISPLAY 0.617021 (3725 2300);
PAINT SKYBLUE (3725 2300);
FORCEPROP 2 LAST CDS_LOCATION R1G8
J 0
(3425 2500);
DISPLAY 0.617021 (3425 2500);
PAINT AQUA (3425 2500);
DISPLAY INVISIBLE (3425 2500);
FORCEPROP 2 LAST CDS_LIB mstr_discrete
J 0
(3475 2450);
PAINT MONO (3475 2450);
DISPLAY INVISIBLE (3475 2450);
FORCEPROP 1 LAST PATH I82
J 0
(3425 2600);
DISPLAY 0.978723 (3425 2600);
PAINT WHITE (3425 2600);
DISPLAY INVISIBLE (3425 2600);
FORCEPROP 2 LAST SEC 1
J 0
(3425 2650);
DISPLAY 0.680851 (3425 2650);
PAINT MONO (3425 2650);
DISPLAY INVISIBLE (3425 2650);
FORCEPROP 2 LAST SEC_TYPE 0402
J 0
(3425 2650);
DISPLAY 1.021277 (3425 2650);
PAINT ORANGE (3425 2650);
DISPLAY INVISIBLE (3425 2650);
FORCEADD RES..1
(-1500 1500);
FORCEPROP 1 LAST VALUE 0.0
J 2
(-1600 1400);
DISPLAY 0.617021 (-1600 1400);
PAINT SKYBLUE (-1600 1400);
FORCEPROP 1 LAST WATTAGE 1/16W
J 2
(-1525 1350);
DISPLAY 0.617021 (-1525 1350);
PAINT SKYBLUE (-1525 1350);
FORCEPROP 1 LAST TOLERANCE 5%
J 0
(-1550 1400);
DISPLAY 0.617021 (-1550 1400);
PAINT SKYBLUE (-1550 1400);
FORCEPROP 1 LAST PART_NUMBER G21497-005
J 0
(-1650 1450);
DISPLAY 0.617021 (-1650 1450);
PAINT BLUE (-1650 1450);
FORCEPROP 1 LAST LOCATION R9U7
J 0
(-1550 1550);
DISPLAY 0.617021 (-1550 1550);
PAINT AQUA (-1550 1550);
FORCEPROP 1 LAST PACK_TYPE 0402
J 0
(-1425 1400);
DISPLAY 0.617021 (-1425 1400);
PAINT SKYBLUE (-1425 1400);
FORCEPROP 1 LAST MATERIAL CHIP
J 0
(-1500 1350);
DISPLAY 0.617021 (-1500 1350);
PAINT SKYBLUE (-1500 1350);
FORCEPROP 1 LASTPIN (-1600 1500) $PN 1
J 0
(-1588 1512);
DISPLAY 0.787234 (-1588 1512);
PAINT ORANGE (-1588 1512);
DISPLAY INVISIBLE (-1588 1512);
FORCEPROP 2 LAST ROOM PVCCIN_CPU0_VR
J 0
(-1550 1600);
DISPLAY 1.361702 (-1550 1600);
PAINT ORANGE (-1550 1600);
DISPLAY INVISIBLE (-1550 1600);
FORCEPROP 1 LAST PATH I84
J 0
(-1550 1650);
DISPLAY 0.978723 (-1550 1650);
PAINT WHITE (-1550 1650);
DISPLAY INVISIBLE (-1550 1650);
FORCEPROP 2 LAST CDS_LOCATION R9U7
J 0
(-1550 1550);
DISPLAY 0.617021 (-1550 1550);
PAINT AQUA (-1550 1550);
DISPLAY INVISIBLE (-1550 1550);
FORCEPROP 2 LAST CDS_SEC 1
J 0
(-1550 1700);
PAINT MONO (-1550 1700);
DISPLAY INVISIBLE (-1550 1700);
FORCEPROP 2 LAST $SEC 1
J 0
(-1550 1700);
PAINT MONO (-1550 1700);
DISPLAY INVISIBLE (-1550 1700);
FORCEPROP 2 LAST CDS_LIB mstr_discrete
J 0
(-1500 1500);
PAINT ORANGE (-1500 1500);
DISPLAY INVISIBLE (-1500 1500);
FORCEPROP 1 LASTPIN (-1400 1500) $PN 2
J 0
(-1438 1512);
DISPLAY 0.787234 (-1438 1512);
PAINT ORANGE (-1438 1512);
DISPLAY INVISIBLE (-1438 1512);
FORCEADD RES..2
(175 3425);
FORCEPROP 1 LAST WATTAGE 1/16W
J 0
(215 3400);
DISPLAY 0.617021 (215 3400);
PAINT SKYBLUE (215 3400);
FORCEPROP 1 LAST PACK_TYPE 0402
J 0
(215 3250);
DISPLAY 0.617021 (215 3250);
PAINT SKYBLUE (215 3250);
FORCEPROP 1 LAST TOLERANCE 1%
J 0
(220 3450);
DISPLAY 0.617021 (220 3450);
PAINT SKYBLUE (220 3450);
FORCEPROP 1 LAST VALUE 100.0K
J 0
(220 3500);
DISPLAY 0.617021 (220 3500);
PAINT SKYBLUE (220 3500);
FORCEPROP 1 LAST PART_NUMBER G21796-010
J 0
(215 3300);
DISPLAY 0.617021 (215 3300);
PAINT BLUE (215 3300);
FORCEPROP 1 LAST LOCATION R9U8
J 0
(220 3550);
DISPLAY 0.617021 (220 3550);
PAINT AQUA (220 3550);
FORCEPROP 1 LAST MATERIAL EMPTY
J 0
(215 3350);
DISPLAY 0.617021 (215 3350);
PAINT RED (215 3350);
FORCEPROP 1 LASTPIN (175 3325) $PN 2
J 0
(180 3335);
DISPLAY 0.787234 (180 3335);
PAINT ORANGE (180 3335);
DISPLAY INVISIBLE (180 3335);
FORCEPROP 2 LAST CDS_LIB mstr_discrete
J 0
(175 3425);
PAINT ORANGE (175 3425);
DISPLAY INVISIBLE (175 3425);
FORCEPROP 1 LASTPIN (175 3525) $PN 1
J 0
(180 3487);
DISPLAY 0.787234 (180 3487);
PAINT ORANGE (180 3487);
DISPLAY INVISIBLE (180 3487);
FORCEPROP 2 LAST CDS_LOCATION R9U8
J 0
(220 3550);
DISPLAY 0.617021 (220 3550);
PAINT AQUA (220 3550);
DISPLAY INVISIBLE (220 3550);
FORCEPROP 0 LAST ROOM BMC
J 0
(225 3650);
DISPLAY 0.617021 (225 3650);
PAINT ORANGE (225 3650);
DISPLAY INVISIBLE (225 3650);
FORCEPROP 1 LAST PATH I85
J 0
(225 3600);
DISPLAY 0.978723 (225 3600);
PAINT WHITE (225 3600);
DISPLAY INVISIBLE (225 3600);
FORCEPROP 2 LAST $SEC 1
J 0
(225 3650);
PAINT MONO (225 3650);
DISPLAY INVISIBLE (225 3650);
FORCEPROP 2 LAST CDS_SEC 1
J 0
(225 3650);
PAINT MONO (225 3650);
DISPLAY INVISIBLE (225 3650);
FORCEPROP 0 LAST BOM_COST SM_CONTROLLER
J 0
(225 3750);
DISPLAY 1.021277 (225 3750);
PAINT ORANGE (225 3750);
DISPLAY INVISIBLE (225 3750);
FORCEADD RES..1
(-1375 2625);
FORCEPROP 1 LAST WATTAGE 1/16W
J 2
(-1400 2475);
DISPLAY 0.617021 (-1400 2475);
PAINT SKYBLUE (-1400 2475);
FORCEPROP 1 LAST VALUE 0.0
J 2
(-1475 2525);
DISPLAY 0.617021 (-1475 2525);
PAINT SKYBLUE (-1475 2525);
FORCEPROP 1 LAST TOLERANCE 5%
J 0
(-1425 2525);
DISPLAY 0.617021 (-1425 2525);
PAINT SKYBLUE (-1425 2525);
FORCEPROP 1 LAST PACK_TYPE 0402
J 0
(-1300 2525);
DISPLAY 0.617021 (-1300 2525);
PAINT SKYBLUE (-1300 2525);
FORCEPROP 1 LAST MATERIAL CHIP
J 0
(-1375 2475);
DISPLAY 0.617021 (-1375 2475);
PAINT SKYBLUE (-1375 2475);
FORCEPROP 1 LAST LOCATION R1G28
J 0
(-1425 2675);
DISPLAY 0.617021 (-1425 2675);
PAINT AQUA (-1425 2675);
FORCEPROP 1 LAST PART_NUMBER G21497-005
J 0
(-1525 2575);
DISPLAY 0.617021 (-1525 2575);
PAINT BLUE (-1525 2575);
FORCEPROP 1 LAST PATH I87
J 0
(-1425 2775);
DISPLAY 0.978723 (-1425 2775);
PAINT WHITE (-1425 2775);
DISPLAY INVISIBLE (-1425 2775);
FORCEPROP 2 LAST CDS_LIB mstr_discrete
J 0
(-1375 2625);
PAINT ORANGE (-1375 2625);
DISPLAY INVISIBLE (-1375 2625);
FORCEPROP 2 LAST ROOM PVCCIN_CPU0_VR
J 0
(-1425 2725);
DISPLAY 1.361702 (-1425 2725);
PAINT ORANGE (-1425 2725);
DISPLAY INVISIBLE (-1425 2725);
FORCEPROP 1 LASTPIN (-1475 2625) $PN 1
J 0
(-1463 2637);
DISPLAY 0.787234 (-1463 2637);
PAINT ORANGE (-1463 2637);
DISPLAY INVISIBLE (-1463 2637);
FORCEPROP 1 LASTPIN (-1275 2625) $PN 2
J 0
(-1313 2637);
DISPLAY 0.787234 (-1313 2637);
PAINT ORANGE (-1313 2637);
DISPLAY INVISIBLE (-1313 2637);
FORCEPROP 2 LAST CDS_SEC 1
J 0
(-1425 2825);
PAINT MONO (-1425 2825);
DISPLAY INVISIBLE (-1425 2825);
FORCEPROP 2 LAST $SEC 1
J 0
(-1425 2825);
PAINT MONO (-1425 2825);
DISPLAY INVISIBLE (-1425 2825);
FORCEADD RES..1
(-600 2800);
FORCEPROP 1 LAST WATTAGE 1/16W
J 2
(-625 2650);
DISPLAY 0.617021 (-625 2650);
PAINT SKYBLUE (-625 2650);
FORCEPROP 1 LAST VALUE 0.0
J 2
(-700 2700);
DISPLAY 0.617021 (-700 2700);
PAINT SKYBLUE (-700 2700);
FORCEPROP 1 LAST TOLERANCE 5%
J 0
(-650 2700);
DISPLAY 0.617021 (-650 2700);
PAINT SKYBLUE (-650 2700);
FORCEPROP 1 LAST MATERIAL CHIP
J 0
(-600 2650);
DISPLAY 0.617021 (-600 2650);
PAINT SKYBLUE (-600 2650);
FORCEPROP 1 LAST PACK_TYPE 0402
J 0
(-525 2700);
DISPLAY 0.617021 (-525 2700);
PAINT SKYBLUE (-525 2700);
FORCEPROP 1 LAST PART_NUMBER G21497-005
J 0
(-750 2750);
DISPLAY 0.617021 (-750 2750);
PAINT BLUE (-750 2750);
FORCEPROP 1 LAST LOCATION R1G27
J 0
(-650 2850);
DISPLAY 0.617021 (-650 2850);
PAINT AQUA (-650 2850);
FORCEPROP 1 LASTPIN (-700 2800) $PN 1
J 0
(-688 2812);
DISPLAY 0.787234 (-688 2812);
PAINT ORANGE (-688 2812);
DISPLAY INVISIBLE (-688 2812);
FORCEPROP 2 LAST CDS_LIB mstr_discrete
J 0
(-600 2800);
PAINT ORANGE (-600 2800);
DISPLAY INVISIBLE (-600 2800);
FORCEPROP 1 LASTPIN (-500 2800) $PN 2
J 0
(-538 2812);
DISPLAY 0.787234 (-538 2812);
PAINT ORANGE (-538 2812);
DISPLAY INVISIBLE (-538 2812);
FORCEPROP 2 LAST $SEC 1
J 0
(-650 3000);
PAINT MONO (-650 3000);
DISPLAY INVISIBLE (-650 3000);
FORCEPROP 1 LAST PATH I88
J 0
(-650 2950);
DISPLAY 0.978723 (-650 2950);
PAINT WHITE (-650 2950);
DISPLAY INVISIBLE (-650 2950);
FORCEPROP 2 LAST ROOM PVCCIN_CPU0_VR
J 0
(-650 2900);
DISPLAY 1.361702 (-650 2900);
PAINT ORANGE (-650 2900);
DISPLAY INVISIBLE (-650 2900);
FORCEPROP 2 LAST CDS_SEC 1
J 0
(-650 3000);
PAINT MONO (-650 3000);
DISPLAY INVISIBLE (-650 3000);
FORCEADD OFFPAGE..1
(-2225 2625);
FORCEPROP 2 LAST $XR0 223 
J 0
(-2507 2625);
DISPLAY 0.638298 (-2507 2625);
PAINT MONO (-2507 2625);
FORCEPROP 2 LAST ROOM VDDQ_GHJ_PWR_VR
J 0
(-2775 2700);
DISPLAY 1.361702 (-2775 2700);
PAINT ORANGE (-2775 2700);
DISPLAY INVISIBLE (-2775 2700);
FORCEPROP 1 LAST COMMENT_BODY TRUE
J 0
(-2100 2525);
DISPLAY 1.170213 (-2100 2525);
PAINT GREEN (-2100 2525);
DISPLAY INVISIBLE (-2100 2525);
FORCEPROP 2 LAST PATH I89
J 0
(-2175 2700);
DISPLAY 1.021277 (-2175 2700);
PAINT ORANGE (-2175 2700);
DISPLAY INVISIBLE (-2175 2700);
FORCEPROP 2 LAST CDS_LIB mstr_standard
J 0
(-2225 2625);
PAINT ORANGE (-2225 2625);
DISPLAY INVISIBLE (-2225 2625);
FORCEPROP 1 LAST OFFPAGE TRUE
J 0
(-1900 2500);
DISPLAY 1.170213 (-1900 2500);
PAINT GREEN (-1900 2500);
DISPLAY INVISIBLE (-1900 2500);
FORCEADD OFFPAGE..2
(4100 2400);
FORCEPROP 2 LAST $XR0 193 
J 0
(4439 2400);
DISPLAY 0.638298 (4439 2400);
PAINT MONO (4439 2400);
FORCEPROP 2 LAST $XR1 226 
J 0
(4559 2400);
DISPLAY 0.638298 (4559 2400);
PAINT MONO (4559 2400);
FORCEPROP 2 LAST $XR2 55 
J 0
(4679 2400);
DISPLAY 0.638298 (4679 2400);
PAINT MONO (4679 2400);
FORCEPROP 1 LAST COMMENT_BODY TRUE
J 0
(4055 2305);
DISPLAY 1.170213 (4055 2305);
PAINT GREEN (4055 2305);
DISPLAY INVISIBLE (4055 2305);
FORCEPROP 2 LAST ROOM VDDQ_GHJ_PWR_VR
J 0
(3675 2475);
DISPLAY 1.361702 (3675 2475);
PAINT ORANGE (3675 2475);
DISPLAY INVISIBLE (3675 2475);
FORCEPROP 2 LAST CDS_LIB mstr_standard
J 0
(4100 2400);
PAINT ORANGE (4100 2400);
DISPLAY INVISIBLE (4100 2400);
FORCEPROP 2 LAST PATH I9
J 0
(4275 2475);
DISPLAY 1.021277 (4275 2475);
PAINT ORANGE (4275 2475);
DISPLAY INVISIBLE (4275 2475);
FORCEPROP 1 LAST OFFPAGE TRUE
J 0
(4425 2275);
DISPLAY 1.170213 (4425 2275);
PAINT GREEN (4425 2275);
DISPLAY INVISIBLE (4425 2275);
FORCEADD PXM1310B..2
(1500 1800);
FORCEPROP 2 LASTPIN (1050 1800) $PN 35
J 2
(1040 1810);
DISPLAY 0.617021 (1040 1810);
PAINT ORANGE (1040 1810);
FORCEPROP 2 LASTPIN (1050 1400) $PN 20
J 2
(1040 1410);
DISPLAY 0.617021 (1040 1410);
PAINT ORANGE (1040 1410);
FORCEPROP 2 LASTPIN (1050 1500) $PN 10
J 2
(1040 1510);
DISPLAY 0.617021 (1040 1510);
PAINT ORANGE (1040 1510);
FORCEPROP 2 LASTPIN (1050 1650) $PN 19
J 2
(1040 1660);
DISPLAY 0.617021 (1040 1660);
PAINT ORANGE (1040 1660);
FORCEPROP 2 LASTPIN (1050 1150) $PN 31
J 2
(1040 1160);
DISPLAY 0.617021 (1040 1160);
PAINT ORANGE (1040 1160);
FORCEPROP 2 LASTPIN (1050 1100) $PN 32
J 2
(1040 1110);
DISPLAY 0.617021 (1040 1110);
PAINT ORANGE (1040 1110);
FORCEPROP 2 LASTPIN (1050 1750) $PN 34
J 2
(1040 1760);
DISPLAY 0.617021 (1040 1760);
PAINT ORANGE (1040 1760);
FORCEPROP 2 LASTPIN (1050 1350) $PN 30
J 2
(1040 1360);
DISPLAY 0.617021 (1040 1360);
PAINT ORANGE (1040 1360);
FORCEPROP 2 LASTPIN (1050 1600) $PN 29
J 2
(1040 1610);
DISPLAY 0.617021 (1040 1610);
PAINT ORANGE (1040 1610);
FORCEPROP 2 LASTPIN (1050 1900) $PN 38
J 2
(1040 1910);
DISPLAY 0.617021 (1040 1910);
PAINT ORANGE (1040 1910);
FORCEPROP 2 LASTPIN (1050 1250) $PN 8
J 2
(1040 1260);
DISPLAY 0.617021 (1040 1260);
PAINT ORANGE (1040 1260);
FORCEPROP 2 LASTPIN (1050 1950) $PN 37
J 2
(1040 1960);
DISPLAY 0.617021 (1040 1960);
PAINT ORANGE (1040 1960);
FORCEPROP 2 LASTPIN (1050 1000) $PN 36
J 2
(1040 1010);
DISPLAY 0.617021 (1040 1010);
PAINT ORANGE (1040 1010);
FORCEPROP 2 LASTPIN (1050 950) $PN 33
J 2
(1040 960);
DISPLAY 0.617021 (1040 960);
PAINT ORANGE (1040 960);
FORCEPROP 1 LAST PART_NUMBER H89186-001
J 0
(1100 850);
DISPLAY 0.617021 (1100 850);
PAINT BLUE (1100 850);
FORCEPROP 2 LASTPIN (1950 1000) $PN 27
J 0
(1960 1010);
DISPLAY 0.617021 (1960 1010);
PAINT ORANGE (1960 1010);
FORCEPROP 2 LASTPIN (1950 1200) $PN 2
J 0
(1960 1210);
DISPLAY 0.617021 (1960 1210);
PAINT ORANGE (1960 1210);
FORCEPROP 2 LASTPIN (1950 1100) $PN 41
J 0
(1960 1110);
DISPLAY 0.617021 (1960 1110);
PAINT ORANGE (1960 1110);
FORCEPROP 2 LASTPIN (1950 1250) $PN 28
J 0
(1960 1260);
DISPLAY 0.617021 (1960 1260);
PAINT ORANGE (1960 1260);
FORCEPROP 2 LASTPIN (1950 1500) $PN 5
J 0
(1960 1510);
DISPLAY 0.617021 (1960 1510);
PAINT ORANGE (1960 1510);
FORCEPROP 2 LASTPIN (1950 1450) $PN 4
J 0
(1960 1460);
DISPLAY 0.617021 (1960 1460);
PAINT ORANGE (1960 1460);
FORCEPROP 2 LASTPIN (1950 1400) $PN 3
J 0
(1960 1410);
DISPLAY 0.617021 (1960 1410);
PAINT ORANGE (1960 1410);
FORCEPROP 2 LASTPIN (1950 1550) $PN 1
J 0
(1960 1560);
DISPLAY 0.617021 (1960 1560);
PAINT ORANGE (1960 1560);
FORCEPROP 2 LASTPIN (1950 1750) $PN 40
J 0
(1960 1760);
DISPLAY 0.617021 (1960 1760);
PAINT ORANGE (1960 1760);
FORCEPROP 2 LASTPIN (1950 1700) $PN 16
J 0
(1960 1710);
DISPLAY 0.617021 (1960 1710);
PAINT ORANGE (1960 1710);
FORCEPROP 2 LASTPIN (1950 1900) $PN 13
J 0
(1960 1910);
DISPLAY 0.617021 (1960 1910);
PAINT ORANGE (1960 1910);
FORCEPROP 2 LASTPIN (1950 1850) $PN 14
J 0
(1960 1860);
DISPLAY 0.617021 (1960 1860);
PAINT ORANGE (1960 1860);
FORCEPROP 2 LASTPIN (1950 2000) $PN 6
J 0
(1960 2010);
DISPLAY 0.617021 (1960 2010);
PAINT ORANGE (1960 2010);
FORCEPROP 2 LASTPIN (1050 2350) $PN 21
J 2
(1040 2360);
DISPLAY 0.617021 (1040 2360);
PAINT ORANGE (1040 2360);
FORCEPROP 2 LASTPIN (1050 2300) $PN 23
J 2
(1040 2310);
DISPLAY 0.617021 (1040 2310);
PAINT ORANGE (1040 2310);
FORCEPROP 2 LASTPIN (1050 2250) $PN 25
J 2
(1040 2260);
DISPLAY 0.617021 (1040 2260);
PAINT ORANGE (1040 2260);
FORCEPROP 2 LASTPIN (1050 2150) $PN 22
J 2
(1040 2160);
DISPLAY 0.617021 (1040 2160);
PAINT ORANGE (1040 2160);
FORCEPROP 2 LASTPIN (1050 2100) $PN 24
J 2
(1040 2110);
DISPLAY 0.617021 (1040 2110);
PAINT ORANGE (1040 2110);
FORCEPROP 2 LASTPIN (1050 2050) $PN 26
J 2
(1040 2060);
DISPLAY 0.617021 (1040 2060);
PAINT ORANGE (1040 2060);
FORCEPROP 2 LASTPIN (1050 2450) $PN 15
J 2
(1040 2460);
DISPLAY 0.617021 (1040 2460);
PAINT ORANGE (1040 2460);
FORCEPROP 2 LASTPIN (1050 2550) $PN 39
J 2
(1040 2560);
DISPLAY 0.617021 (1040 2560);
PAINT ORANGE (1040 2560);
FORCEPROP 1 LAST MATERIAL IC
J 0
(1100 2725);
DISPLAY 0.617021 (1100 2725);
PAINT SKYBLUE (1100 2725);
FORCEPROP 1 LAST LOCATION EU1G2
J 0
(1100 2775);
DISPLAY 0.617021 (1100 2775);
PAINT AQUA (1100 2775);
FORCEPROP 2 LASTPIN (1950 2250) $PN 18
J 0
(1960 2260);
DISPLAY 0.617021 (1960 2260);
PAINT ORANGE (1960 2260);
FORCEPROP 2 LASTPIN (1950 2150) $PN 12
J 0
(1960 2160);
DISPLAY 0.617021 (1960 2160);
PAINT ORANGE (1960 2160);
FORCEPROP 2 LASTPIN (1950 2050) $PN 7
J 0
(1960 2060);
DISPLAY 0.617021 (1960 2060);
PAINT ORANGE (1960 2060);
FORCEPROP 2 LASTPIN (1950 2450) $PN 11
J 0
(1960 2460);
DISPLAY 0.617021 (1960 2460);
PAINT ORANGE (1960 2460);
FORCEPROP 2 LASTPIN (1950 2400) $PN 17
J 0
(1960 2410);
DISPLAY 0.617021 (1960 2410);
PAINT ORANGE (1960 2410);
FORCEPROP 2 LASTPIN (1950 2550) $PN 9
J 0
(1960 2560);
DISPLAY 0.617021 (1960 2560);
PAINT ORANGE (1960 2560);
FORCEPROP 1 LAST CDS_LMAN_SYM_OUTLINE -400,900,400,-900
J 0
(1500 1800);
DISPLAY 0.468085 (1500 1800);
PAINT GREEN (1500 1800);
DISPLAY INVISIBLE (1500 1800);
FORCEPROP 2 LAST CDS_LIB mstr_controller
J 0
(1500 1800);
PAINT ORANGE (1500 1800);
DISPLAY INVISIBLE (1500 1800);
FORCEPROP 2 LAST CDS_LOCATION EU1G2
J 0
(1100 2775);
PAINT WHITE (1100 2775);
DISPLAY INVISIBLE (1100 2775);
FORCEPROP 1 LAST PACK_TYPE QFN
J 0
(1100 2825);
PAINT SKYBLUE (1100 2825);
DISPLAY INVISIBLE (1100 2825);
FORCEPROP 2 LAST SEC_TYPE QFN
J 0
(1100 2825);
DISPLAY 1.021277 (1100 2825);
PAINT ORANGE (1100 2825);
DISPLAY INVISIBLE (1100 2825);
FORCEPROP 2 LAST SEC 1
J 0
(1100 2825);
DISPLAY 0.680851 (1100 2825);
PAINT MONO (1100 2825);
DISPLAY INVISIBLE (1100 2825);
FORCEPROP 1 LAST PATH I90
J 0
(1600 2726);
PAINT WHITE (1600 2726);
DISPLAY INVISIBLE (1600 2726);
FORCEADD GND..1
(-325 125);
FORCEPROP 3 LASTPIN (-325 175) SIG_NAME GND\g
J 0
(-315 185);
DISPLAY 0.659574 (-315 185);
PAINT MONO (-315 185);
DISPLAY INVISIBLE (-315 185);
FORCEPROP 1 LAST BODY_TYPE PLUMBING
J 0
(-370 82);
DISPLAY 0.340426 (-370 82);
PAINT GREEN (-370 82);
DISPLAY INVISIBLE (-370 82);
FORCEPROP 2 LAST CDS_LIB mstr_symbols
J 0
(-325 125);
PAINT ORANGE (-325 125);
DISPLAY INVISIBLE (-325 125);
FORCEPROP 1 LAST VOLTAGE 0.0V
J 0
(-370 82);
DISPLAY 0.340426 (-370 82);
PAINT SKYBLUE (-370 82);
DISPLAY INVISIBLE (-370 82);
FORCEPROP 1 LAST HDL_POWER GND
J 0
(-325 275);
DISPLAY 1.170213 (-325 275);
PAINT GREEN (-325 275);
DISPLAY INVISIBLE (-325 275);
FORCEPROP 1 LAST PATH I91
J 0
(-250 125);
DISPLAY 0.872340 (-250 125);
PAINT AQUA (-250 125);
DISPLAY INVISIBLE (-250 125);
FORCEPROP 1 LAST SIZE 1B
J 0
(-250 75);
DISPLAY 1.170213 (-250 75);
PAINT AQUA (-250 75);
DISPLAY INVISIBLE (-250 75);
FORCEADD CAP_A..1
R 2
(-325 450);
FORCEPROP 1 LAST PACK_TYPE 0402V
J 2
(-375 250);
DISPLAY 0.617021 (-375 250);
PAINT SKYBLUE (-375 250);
FORCEPROP 1 LAST VALUE 0.1UF
J 2
(-375 500);
DISPLAY 0.617021 (-375 500);
PAINT SKYBLUE (-375 500);
FORCEPROP 1 LAST PART_NUMBER A36096-030
J 2
(-375 300);
DISPLAY 0.617021 (-375 300);
PAINT BLUE (-375 300);
FORCEPROP 1 LAST LOCATION C9U12
J 2
(-375 550);
DISPLAY 0.617021 (-375 550);
PAINT AQUA (-375 550);
FORCEPROP 1 LASTPIN (-325 350) $PN 2
J 2
(-335 330);
DISPLAY 0.617021 (-335 330);
PAINT ORANGE (-335 330);
FORCEPROP 1 LAST MATERIAL X7R
J 2
(-375 350);
DISPLAY 0.617021 (-375 350);
PAINT SKYBLUE (-375 350);
FORCEPROP 1 LAST VOLTAGE 16V
J 2
(-375 450);
DISPLAY 0.617021 (-375 450);
PAINT SKYBLUE (-375 450);
FORCEPROP 1 LAST TOLERANCE 10%
J 2
(-375 400);
DISPLAY 0.617021 (-375 400);
PAINT SKYBLUE (-375 400);
FORCEPROP 1 LASTPIN (-325 550) $PN 1
J 2
(-335 530);
DISPLAY 0.617021 (-335 530);
PAINT ORANGE (-335 530);
FORCEPROP 2 LAST CDS_LIB dev_discrete
J 0
(-325 450);
PAINT ORANGE (-325 450);
DISPLAY INVISIBLE (-325 450);
FORCEPROP 2 LAST SEC 1
J 0
(-375 650);
DISPLAY 0.680851 (-375 650);
PAINT MONO (-375 650);
DISPLAY INVISIBLE (-375 650);
FORCEPROP 2 LAST SEC_TYPE 0402V
J 0
(-375 650);
DISPLAY 1.021277 (-375 650);
PAINT ORANGE (-375 650);
DISPLAY INVISIBLE (-375 650);
FORCEPROP 2 LAST CDS_SEC 1
J 0
(-375 600);
PAINT ORANGE (-375 600);
DISPLAY INVISIBLE (-375 600);
FORCEPROP 0 LAST ROOM VDDQ_GHJ_PWR_VR
J 0
(-375 600);
DISPLAY 1.021277 (-375 600);
PAINT ORANGE (-375 600);
DISPLAY INVISIBLE (-375 600);
FORCEPROP 1 LAST PATH I92
J 2
(-375 600);
DISPLAY 0.978723 (-375 600);
PAINT WHITE (-375 600);
DISPLAY INVISIBLE (-375 600);
FORCEADD DESIGN_NOTE..1
(975 650);
FORCEPROP 0 LAST L2 SVID ADDRESS=0X0
J 0
(780 465);
DISPLAY 1.021277 (780 465);
PAINT ORANGE (780 465);
FORCEPROP 0 LAST L1 SMBUS ADDRESS: 0X70
J 0
(775 525);
DISPLAY 1.021277 (775 525);
PAINT ORANGE (775 525);
FORCEPROP 1 LAST COMMENT_BODY TRUE
J 0
(1000 750);
DISPLAY 0.978723 (1000 750);
PAINT ORANGE (1000 750);
DISPLAY INVISIBLE (1000 750);
FORCEPROP 2 LAST CDS_LIB mstr_symbols
J 0
(975 650);
PAINT ORANGE (975 650);
DISPLAY INVISIBLE (975 650);
FORCEADD DNS..2
(-620 3345);
PAINT RED (-620 3345);
FORCEPROP 1 LAST COMMENT_BODY TRUE
R 1
J 0
(-545 3120);
DISPLAY 0.872340 (-545 3120);
PAINT GREEN (-545 3120);
DISPLAY INVISIBLE (-545 3120);
FORCEPROP 2 LAST CDS_LIB mstr_misc
J 0
(-620 3345);
PAINT ORANGE (-620 3345);
DISPLAY INVISIBLE (-620 3345);
FORCEADD DNS..2
(2705 3095);
PAINT RED (2705 3095);
FORCEPROP 1 LAST COMMENT_BODY TRUE
R 1
J 0
(2780 2870);
DISPLAY 0.872340 (2780 2870);
PAINT GREEN (2780 2870);
DISPLAY INVISIBLE (2780 2870);
FORCEPROP 2 LAST CDS_LIB mstr_misc
J 0
(2705 3095);
PAINT ORANGE (2705 3095);
DISPLAY INVISIBLE (2705 3095);
FORCEADD DESIGN_NOTE..1
(4325 3925);
PAINT PURPLE (4325 3925);
FORCEPROP 0 LAST L2 SVID ADDRESS=0X0
J 0
(4155 3740);
DISPLAY 1.021277 (4155 3740);
PAINT ORANGE (4155 3740);
FORCEPROP 0 LAST L1 SMBUS ADDRESS 0X70
J 0
(4150 3800);
PAINT VIOLET (4150 3800);
FORCEPROP 2 LAST BOM_COST VDDQ_GHJ_VR
J 0
(4125 3875);
PAINT MONO (4125 3875);
DISPLAY INVISIBLE (4125 3875);
FORCEPROP 2 LAST CDS_LIB mstr_symbols
J 0
(4325 3925);
PAINT MONO (4325 3925);
DISPLAY INVISIBLE (4325 3925);
FORCEPROP 1 LAST COMMENT_BODY TRUE
J 0
(4350 4025);
DISPLAY 1.319149 (4350 4025);
PAINT GREEN (4350 4025);
DISPLAY INVISIBLE (4350 4025);
FORCEPROP 2 LAST ROOM VDDQ_GHJ_PWR_VR
J 0
(4125 3875);
PAINT MONO (4125 3875);
DISPLAY INVISIBLE (4125 3875);
FORCEADD DNS..2
(180 3420);
PAINT RED (180 3420);
FORCEPROP 1 LAST COMMENT_BODY TRUE
R 1
J 0
(255 3195);
DISPLAY 0.872340 (255 3195);
PAINT GREEN (255 3195);
DISPLAY INVISIBLE (255 3195);
FORCEPROP 2 LAST CDS_LIB mstr_misc
J 0
(180 3420);
PAINT ORANGE (180 3420);
DISPLAY INVISIBLE (180 3420);
FORCEADD INTEL_CORP_BPAGE..1
(5250 -875);
FORCEPROP 1 LAST CDS_CON_LAST_MODIFIED Tue Dec 01 11:52:27 2015
J 0
(3825 -550);
DISPLAY 0.744681 (3825 -550);
PAINT GREEN (3825 -550);
DISPLAY INVISIBLE (3825 -550);
FORCEPROP 1 LAST CUSTOM_TXT_CDS <CURRENT_DESIGN_SHEET> OF <TOTAL_DESIGN_SHEETS>
J 0
(4750 -850);
PAINT GREEN (4750 -850);
FORCEPROP 1 LAST CUSTOM_TXT_CDS <CON_LAST_MODIFIED>
J 0
(3325 -525);
PAINT GREEN (3325 -525);
FORCEPROP 2 LAST CUSTOM_TXT_CDS <XR_PAGE_TITLE>
J 0
(-2640 4375);
DISPLAY 0.638298 (-2640 4375);
PAINT PINK (-2640 4375);
DISPLAY INVISIBLE (-2640 4375);
FORCEPROP 1 LAST SCH_TITLE VDDQ GHJ_VR (1 OF 3)
J 0
(-2725 -850);
DISPLAY 1.212766 (-2725 -850);
PAINT ORANGE (-2725 -850);
FORCEPROP 1 LAST SCH_ADDRESS1 2200 Mission College Blvd.
J 0
(1275 -750);
DISPLAY 0.617021 (1275 -750);
PAINT GREEN (1275 -750);
FORCEPROP 1 LAST SCH_ADDRESS2 P.O. BOX 58119
J 0
(1275 -800);
DISPLAY 0.617021 (1275 -800);
PAINT GREEN (1275 -800);
FORCEPROP 1 LAST SCH_ADDRESS3 Santa Clara, CA 95052-8119
J 0
(1275 -850);
DISPLAY 0.617021 (1275 -850);
PAINT GREEN (1275 -850);
FORCEPROP 1 LAST SCH_NUMBER H4694802
J 0
(3950 -725);
DISPLAY 1.212766 (3950 -725);
PAINT YELLOW (3950 -725);
FORCEPROP 1 LAST SCH_DEPT BESD
J 1
(800 -775);
DISPLAY 1.212766 (800 -775);
PAINT YELLOW (800 -775);
FORCEPROP 1 LAST SCH_REV 2.420
J 0
(5000 -725);
DISPLAY 0.978723 (5000 -725);
PAINT YELLOW (5000 -725);
FORCEPROP 2 LAST PAGE_BORDER TRUE
J 0
(-2640 4375);
DISPLAY 0.638298 (-2640 4375);
PAINT PINK (-2640 4375);
DISPLAY INVISIBLE (-2640 4375);
FORCEPROP 1 LAST COMMENT_BODY TRUE
J 0
(5262 -863);
DISPLAY 0.340426 (5262 -863);
PAINT GREEN (5262 -863);
DISPLAY INVISIBLE (5262 -863);
FORCEPROP 2 LAST CDS_LIB mstr_symbols
J 0
(5250 -875);
DISPLAY 0.744681 (5250 -875);
PAINT ORANGE (5250 -875);
DISPLAY INVISIBLE (5250 -875);
FORCEPROP 2 LAST ROOM VDDQ_GHJ_PWR_VR
J 0
(4800 4275);
DISPLAY 0.744681 (4800 4275);
PAINT ORANGE (4800 4275);
DISPLAY INVISIBLE (4800 4275);
FORCEPROP 2 LAST CDS_XR_PAGE_TITLE CR-223 : @BASEBOARD_FAB2_LIB.BASEBOARD_FAB2(SCH_1):PAGE223
J 0
(-2640 4375);
DISPLAY 0.638298 (-2640 4375);
PAINT PINK (-2640 4375);
DISPLAY INVISIBLE (-2640 4375);
WIRE 16 -1 (2200 3550)(2400 3550);
WIRE 16 -1 (2200 3550)(2200 3225);
WIRE 16 -1 (2400 3200)(2400 3550);
WIRE 16 -1 (2475 3550)(2400 3550);
WIRE 16 -1 (2700 3550)(2475 3550);
WIRE 16 -1 (2475 3550)(2475 3750);
WIRE 16 -1 (2700 3200)(2700 3550);
WIRE 16 -1 (1950 1100)(2075 1100);
WIRE 16 -1 (2075 1100)(2075 1000);
WIRE 16 -1 (1950 1000)(2075 1000);
WIRE 16 -1 (2075 875)(2075 1000);
WIRE 16 -1 (1600 2950)(1600 3000);
WIRE 16 -1 (1200 2950)(1200 3000);
WIRE 16 -1 (175 3525)(175 3625);
WIRE 16 -1 (175 3625)(900 3625);
WIRE 16 -1 (900 3550)(900 3625);
WIRE 16 -1 (900 3625)(900 3725);
WIRE 16 -1 (1050 1100)(175 1100);
WIRE 16 -1 (175 1100)(175 900);
WIRE 16 -1 (3775 -125)(3775 25);
WIRE 16 -1 (3375 -25)(3375 25);
WIRE 16 -1 (625 100)(625 200);
WIRE 16 -1 (275 100)(275 200);
WIRE 16 -1 (100 100)(100 650);
WIRE 16 -1 (-625 3450)(-625 3875);
WIRE 16 -1 (-1175 3800)(-1175 3875);
WIRE 16 -1 (-1175 3175)(-1175 3250);
WIRE 16 -1 (-1400 3175)(-1400 3250);
WIRE 16 -1 (3925 2900)(3925 2950);
WIRE 16 -1 (3050 900)(3050 750);
WIRE 16 -1 (-325 175)(-325 350);
WIRE 16 -1 (1050 1400)(-675 1400);
WIRE 16 -1 (-675 800)(-675 1400);
WIRE 16 -1 (-1450 800)(-675 800);
WIRE 16 -1 (-1450 825)(-1450 800);
WIRE 16 -1 (-1450 800)(-2225 800);
FORCEPROP 2 LAST SIG_NAME VSENSE_PVDDQ_GHJ_N
J 0
(-2240 815);
DISPLAY 0.617021 (-2240 815);
PAINT ORANGE (-2240 815);
WIRE 16 2175 (4975 3650)(4975 3150);
WIRE 16 2175 (4975 3650)(4050 3650);
WIRE 16 2175 (4975 3150)(4050 3150);
WIRE 16 2175 (4050 3150)(4050 3650);
WIRE 16 -1 (3775 225)(3775 300);
WIRE 16 -1 (3775 300)(4375 300);
WIRE 16 -1 (3775 300)(3375 300);
FORCEPROP 2 LAST SIG_NAME VR_PVDDQ_GHJ_VD12
J 0
(3460 315);
DISPLAY 0.617021 (3460 315);
PAINT ORANGE (3460 315);
WIRE 16 -1 (3375 225)(3375 300);
WIRE 16 -1 (4225 2450)(3575 2450);
FORCEPROP 2 LAST SIG_NAME IRQ_PVDDQ_GHJ_VRHOT_LVT3_N
J 0
(3610 2465);
DISPLAY 0.617021 (3610 2465);
PAINT ORANGE (3610 2465);
WIRE 16 -1 (3375 2550)(4050 2550);
FORCEPROP 2 LAST SIG_NAME PWRGD_PVDDQ_GHJ
J 0
(3535 2565);
DISPLAY 0.617021 (3535 2565);
PAINT ORANGE (3535 2565);
WIRE 16 -1 (3275 2050)(4050 2050);
FORCEPROP 2 LAST SIG_NAME SMB_VR_STBY_LVC3_SCL
J 0
(3435 2065);
DISPLAY 0.617021 (3435 2065);
PAINT ORANGE (3435 2065);
WIRE 16 -1 (3175 2550)(3050 2550);
WIRE 16 -1 (3050 2550)(2400 2550);
FORCEPROP 2 LAST SIG_NAME PWRGD_PVDDQ_GHJ_R
J 0
(2585 2565);
DISPLAY 0.617021 (2585 2565);
PAINT ORANGE (2585 2565);
FORCEPROP 2 LASTPROP $XRERR UNIQUE?
J 0
(2345 2565);
DISPLAY 0.638298 (2345 2565);
PAINT MONO (2345 2565);
DISPLAY INVISIBLE (2345 2565);
WIRE 16 -1 (3050 2550)(3050 1100);
WIRE 16 -1 (2400 3000)(2400 2550);
WIRE 16 -1 (1950 2550)(2400 2550);
WIRE 16 -1 (3375 2450)(2200 2450);
FORCEPROP 2 LAST SIG_NAME IRQ_PVDDQ_GHJ_VRHOT_LVT3_R_N
J 0
(2035 2465);
DISPLAY 0.617021 (2035 2465);
PAINT ORANGE (2035 2465);
FORCEPROP 2 LASTPROP $XRERR UNIQUE?
J 0
(1795 2465);
DISPLAY 0.638298 (1795 2465);
PAINT MONO (1795 2465);
DISPLAY INVISIBLE (1795 2465);
WIRE 16 -1 (2200 3025)(2200 2450);
WIRE 16 -1 (2200 2450)(1950 2450);
WIRE 16 -1 (2975 2400)(4050 2400);
FORCEPROP 2 LAST SIG_NAME SVID_ALERT1_CPU1_R_N
J 0
(3525 2410);
DISPLAY 0.617021 (3525 2410);
PAINT ORANGE (3525 2410);
WIRE 16 -1 (4050 1700)(3925 1700);
WIRE 16 -1 (3925 2700)(3925 1700);
WIRE 16 -1 (2950 1700)(3925 1700);
FORCEPROP 2 LAST SIG_NAME SVID_DIO1_CPU1_R
J 0
(3600 1710);
DISPLAY 0.617021 (3600 1710);
PAINT ORANGE (3600 1710);
WIRE 16 -1 (2700 3000)(2700 1900);
WIRE 16 -1 (1950 1900)(2700 1900);
FORCEPROP 2 LAST SIG_NAME PU_VR_PVDDQ_GHJ_FAULT1
J 0
(2060 1915);
DISPLAY 0.617021 (2060 1915);
PAINT ORANGE (2060 1915);
FORCEPROP 2 LASTPROP $XRERR UNIQUE?
J 0
(1820 1915);
DISPLAY 0.638298 (1820 1915);
PAINT MONO (1820 1915);
DISPLAY INVISIBLE (1820 1915);
WIRE 16 -1 (2950 2000)(4050 2000);
FORCEPROP 2 LAST SIG_NAME SMB_VR_STBY_LVC3_SDA
J 0
(3435 2015);
DISPLAY 0.617021 (3435 2015);
PAINT ORANGE (3435 2015);
WIRE 16 -1 (2775 2400)(1950 2400);
FORCEPROP 2 LAST SIG_NAME SVID_ALERT_PVDDQ_GHJ
J 0
(2050 2415);
DISPLAY 0.617021 (2050 2415);
PAINT ORANGE (2050 2415);
FORCEPROP 2 LASTPROP $XRERR UNIQUE?
J 0
(1810 2415);
DISPLAY 0.638298 (1810 2415);
PAINT MONO (1810 2415);
DISPLAY INVISIBLE (1810 2415);
WIRE 16 -1 (1950 2250)(2500 2250);
FORCEPROP 2 LAST SIG_NAME TP_PVDDQ_GHJ_MP2
J 0
(2050 2265);
DISPLAY 0.617021 (2050 2265);
PAINT ORANGE (2050 2265);
FORCEPROP 2 LASTPROP $XRERR UNIQUE?
J 0
(2530 2250);
DISPLAY 0.638298 (2530 2250);
PAINT MONO (2530 2250);
DISPLAY INVISIBLE (2530 2250);
WIRE 16 -1 (1950 1550)(2650 1550);
FORCEPROP 2 LAST SIG_NAME TP_PVDDQ_GHJ_BPWM1
J 0
(2050 1565);
DISPLAY 0.617021 (2050 1565);
PAINT ORANGE (2050 1565);
FORCEPROP 2 LASTPROP $XRERR UNIQUE?
J 0
(2680 1550);
DISPLAY 0.638298 (2680 1550);
PAINT MONO (2680 1550);
DISPLAY INVISIBLE (2680 1550);
WIRE 16 -1 (1950 1400)(2750 1400);
FORCEPROP 2 LAST SIG_NAME TP_PVDDQ_GHJ_PWM3
J 0
(2050 1415);
DISPLAY 0.617021 (2050 1415);
PAINT ORANGE (2050 1415);
FORCEPROP 2 LASTPROP $XRERR UNIQUE?
J 0
(2780 1400);
DISPLAY 0.638298 (2780 1400);
PAINT MONO (2780 1400);
DISPLAY INVISIBLE (2780 1400);
WIRE 16 -1 (1950 2000)(2750 2000);
FORCEPROP 2 LAST SIG_NAME SMB_VR_SDA_VDDQ_GHJ
J 0
(2050 2015);
DISPLAY 0.617021 (2050 2015);
PAINT ORANGE (2050 2015);
FORCEPROP 2 LASTPROP $XRERR UNIQUE?
J 0
(1810 2015);
DISPLAY 0.638298 (1810 2015);
PAINT MONO (1810 2015);
DISPLAY INVISIBLE (1810 2015);
WIRE 16 -1 (1950 2050)(3075 2050);
FORCEPROP 2 LAST SIG_NAME SMB_VR_SCL_VDDQ_GHJ
J 0
(2050 2065);
DISPLAY 0.617021 (2050 2065);
PAINT ORANGE (2050 2065);
FORCEPROP 2 LASTPROP $XRERR UNIQUE?
J 0
(1810 2065);
DISPLAY 0.638298 (1810 2065);
PAINT MONO (1810 2065);
DISPLAY INVISIBLE (1810 2065);
WIRE 16 -1 (1950 1700)(2750 1700);
FORCEPROP 2 LAST SIG_NAME SVID_VDIO_PVDDQ_GHJ
J 0
(2050 1715);
DISPLAY 0.617021 (2050 1715);
PAINT ORANGE (2050 1715);
FORCEPROP 2 LASTPROP $XRERR UNIQUE?
J 0
(1810 1715);
DISPLAY 0.638298 (1810 1715);
PAINT MONO (1810 1715);
DISPLAY INVISIBLE (1810 1715);
WIRE 16 -1 (1950 1200)(2650 1200);
FORCEPROP 2 LAST SIG_NAME NC_PVDDQ_GHJ_DNC0
J 0
(2050 1215);
DISPLAY 0.617021 (2050 1215);
PAINT ORANGE (2050 1215);
FORCEPROP 2 LASTPROP $XRERR UNIQUE?
J 0
(2680 1200);
DISPLAY 0.638298 (2680 1200);
PAINT MONO (2680 1200);
DISPLAY INVISIBLE (2680 1200);
WIRE 16 -1 (1950 1250)(2650 1250);
FORCEPROP 2 LAST SIG_NAME NC_PVDDQ_GHJ_DNC1
J 0
(2050 1265);
DISPLAY 0.617021 (2050 1265);
PAINT ORANGE (2050 1265);
FORCEPROP 2 LASTPROP $XRERR UNIQUE?
J 0
(2680 1250);
DISPLAY 0.638298 (2680 1250);
PAINT MONO (2680 1250);
DISPLAY INVISIBLE (2680 1250);
WIRE 16 -1 (1950 2150)(2650 2150);
FORCEPROP 2 LAST SIG_NAME NC_PVDDQ_GHJ_PINALRT_N
J 0
(2050 2165);
DISPLAY 0.617021 (2050 2165);
PAINT ORANGE (2050 2165);
FORCEPROP 2 LASTPROP $XRERR UNIQUE?
J 0
(2680 2150);
DISPLAY 0.638298 (2680 2150);
PAINT MONO (2680 2150);
DISPLAY INVISIBLE (2680 2150);
WIRE 16 -1 (1950 1850)(2650 1850);
FORCEPROP 2 LAST SIG_NAME TP_PVDDQ_GHJ_MP1
J 0
(2050 1865);
DISPLAY 0.617021 (2050 1865);
PAINT ORANGE (2050 1865);
FORCEPROP 2 LASTPROP $XRERR UNIQUE?
J 0
(2680 1850);
DISPLAY 0.638298 (2680 1850);
PAINT MONO (2680 1850);
DISPLAY INVISIBLE (2680 1850);
WIRE 16 -1 (4075 1750)(1950 1750);
FORCEPROP 2 LAST SIG_NAME VR_PVDDQ_GHJ_VD12
J 0
(3385 1765);
DISPLAY 0.617021 (3385 1765);
PAINT ORANGE (3385 1765);
WIRE 16 -1 (4075 1500)(1950 1500);
FORCEPROP 2 LAST SIG_NAME VR_PVDDQ_GHJ_PWM1
J 0
(3375 1515);
DISPLAY 0.617021 (3375 1515);
PAINT ORANGE (3375 1515);
WIRE 16 -1 (1950 1450)(4075 1450);
FORCEPROP 2 LAST SIG_NAME VR_PVDDQ_GHJ_PWM2
J 0
(3375 1465);
DISPLAY 0.617021 (3375 1465);
PAINT ORANGE (3375 1465);
WIRE 16 -1 (1600 3200)(1600 3250);
WIRE 16 -1 (1600 3250)(1200 3250);
FORCEPROP 2 LAST SIG_NAME VR_PVDDQ_GHJ_VDD
J 0
(1160 3265);
DISPLAY 0.617021 (1160 3265);
PAINT ORANGE (1160 3265);
FORCEPROP 2 LASTPROP $XRERR UNIQUE?
J 0
(920 3265);
DISPLAY 0.638298 (920 3265);
PAINT MONO (920 3265);
DISPLAY INVISIBLE (920 3265);
WIRE 16 -1 (1200 3200)(1200 3250);
WIRE 16 -1 (1200 3250)(900 3250);
WIRE 16 -1 (900 3350)(900 3250);
WIRE 16 -1 (900 3250)(900 2550);
WIRE 16 -1 (1050 2550)(900 2550);
WIRE 16 -1 (725 2450)(1050 2450);
WIRE 16 -1 (725 2975)(725 2450);
WIRE 16 -1 (-125 2975)(725 2975);
FORCEPROP 2 LAST SIG_NAME SVID_CLK_PVDDQ_GHJ
J 0
(210 2990);
DISPLAY 0.617021 (210 2990);
PAINT ORANGE (210 2990);
FORCEPROP 2 LASTPROP $XRERR UNIQUE?
J 0
(-30 2990);
DISPLAY 0.638298 (-30 2990);
PAINT MONO (-30 2990);
DISPLAY INVISIBLE (-30 2990);
WIRE 16 -1 (250 2050)(1050 2050);
FORCEPROP 2 LAST SIG_NAME TP_PVDDQ_GHJ_PH3_IMON
J 0
(225 2065);
DISPLAY 0.617021 (225 2065);
PAINT ORANGE (225 2065);
FORCEPROP 2 LASTPROP $XRERR UNIQUE?
J 0
(10 2050);
DISPLAY 0.638298 (10 2050);
PAINT MONO (10 2050);
DISPLAY INVISIBLE (10 2050);
WIRE 16 -1 (250 2250)(1050 2250);
FORCEPROP 2 LAST SIG_NAME TP_PVDDQ_GHJ_PH3_IMON_REF
J 0
(225 2265);
DISPLAY 0.617021 (225 2265);
PAINT ORANGE (225 2265);
FORCEPROP 2 LASTPROP $XRERR UNIQUE?
J 0
(10 2250);
DISPLAY 0.638298 (10 2250);
PAINT MONO (10 2250);
DISPLAY INVISIBLE (10 2250);
WIRE 16 -1 (175 1500)(175 3325);
WIRE 16 -1 (175 1500)(1050 1500);
WIRE 16 -1 (-1400 1500)(175 1500);
FORCEPROP 2 LAST SIG_NAME VR_PVDDQ_GHJ_VREN
J 0
(-1285 1500);
DISPLAY 0.617021 (-1285 1500);
PAINT ORANGE (-1285 1500);
FORCEPROP 2 LASTPROP $XRERR UNIQUE?
J 0
(-1525 1500);
DISPLAY 0.638298 (-1525 1500);
PAINT MONO (-1525 1500);
DISPLAY INVISIBLE (-1525 1500);
WIRE 16 -1 (100 850)(100 1800);
WIRE 16 -1 (100 1800)(1050 1800);
WIRE 16 -1 (-2125 1800)(100 1800);
FORCEPROP 2 LAST SIG_NAME A_TSENSE_PVDDQ_GHJ
J 0
(-2150 1815);
DISPLAY 0.617021 (-2150 1815);
PAINT ORANGE (-2150 1815);
WIRE 16 -1 (275 1000)(1050 1000);
WIRE 16 -1 (275 400)(275 1000);
FORCEPROP 0 LAST SIG_NAME VR_PVDDQ_GHJ_XADDR1
R 1
J 0
(265 435);
DISPLAY 0.617021 (265 435);
PAINT ORANGE (265 435);
FORCEPROP 2 LASTPROP $XRERR UNIQUE?
J 0
(25 435);
DISPLAY 0.638298 (25 435);
PAINT MONO (25 435);
DISPLAY INVISIBLE (25 435);
WIRE 16 -1 (350 1150)(1050 1150);
FORCEPROP 2 LAST SIG_NAME TP_PVDDQ_GHJ_BREF1
J 0
(450 1165);
DISPLAY 0.617021 (450 1165);
PAINT ORANGE (450 1165);
FORCEPROP 2 LASTPROP $XRERR UNIQUE?
J 0
(110 1150);
DISPLAY 0.638298 (110 1150);
PAINT MONO (110 1150);
DISPLAY INVISIBLE (110 1150);
WIRE 16 -1 (350 1350)(1050 1350);
FORCEPROP 2 LAST SIG_NAME TP_PVDDQ_GHJ_BVREF
J 0
(450 1365);
DISPLAY 0.617021 (450 1365);
PAINT ORANGE (450 1365);
FORCEPROP 2 LASTPROP $XRERR UNIQUE?
J 0
(110 1350);
DISPLAY 0.638298 (110 1350);
PAINT MONO (110 1350);
DISPLAY INVISIBLE (110 1350);
WIRE 16 -1 (350 1600)(1050 1600);
FORCEPROP 2 LAST SIG_NAME TP_PVDDQ_GHJ_BVSEN
J 0
(450 1615);
DISPLAY 0.617021 (450 1615);
PAINT ORANGE (450 1615);
FORCEPROP 2 LASTPROP $XRERR UNIQUE?
J 0
(110 1600);
DISPLAY 0.638298 (110 1600);
PAINT MONO (110 1600);
DISPLAY INVISIBLE (110 1600);
WIRE 16 -1 (350 1250)(1050 1250);
FORCEPROP 2 LAST SIG_NAME TP_PVDDQ_GHJ_RESET_N
J 0
(450 1265);
DISPLAY 0.617021 (450 1265);
PAINT ORANGE (450 1265);
FORCEPROP 2 LASTPROP $XRERR UNIQUE?
J 0
(110 1250);
DISPLAY 0.638298 (110 1250);
PAINT MONO (110 1250);
DISPLAY INVISIBLE (110 1250);
WIRE 16 -1 (625 950)(1050 950);
WIRE 16 -1 (625 400)(625 950);
FORCEPROP 0 LAST SIG_NAME VR_PVDDQ_GHJ_XADDR2
R 1
J 0
(615 410);
DISPLAY 0.617021 (615 410);
PAINT ORANGE (615 410);
FORCEPROP 2 LASTPROP $XRERR UNIQUE?
J 0
(375 410);
DISPLAY 0.638298 (375 410);
PAINT MONO (375 410);
DISPLAY INVISIBLE (375 410);
WIRE 16 -1 (350 1750)(1050 1750);
FORCEPROP 2 LAST SIG_NAME TP_PVDDQ_GHJ_BTSEN
J 0
(450 1765);
DISPLAY 0.617021 (450 1765);
PAINT ORANGE (450 1765);
FORCEPROP 2 LASTPROP $XRERR UNIQUE?
J 0
(110 1750);
DISPLAY 0.638298 (110 1750);
PAINT MONO (110 1750);
DISPLAY INVISIBLE (110 1750);
WIRE 16 -1 (1050 1650)(-750 1650);
WIRE 16 -1 (-750 1075)(-750 1650);
WIRE 16 -1 (-1450 1075)(-750 1075);
FORCEPROP 2 LAST SIG_NAME VR_PVDDQ_GHJ_AVSP
J 0
(-1365 1090);
DISPLAY 0.617021 (-1365 1090);
PAINT ORANGE (-1365 1090);
FORCEPROP 2 LASTPROP $XRERR UNIQUE?
J 0
(-1605 1090);
DISPLAY 0.638298 (-1605 1090);
PAINT MONO (-1605 1090);
DISPLAY INVISIBLE (-1605 1090);
WIRE 16 -1 (-1450 1025)(-1450 1075);
WIRE 16 -1 (-1625 1075)(-1450 1075);
WIRE 16 -1 (-1225 2350)(1050 2350);
WIRE 16 -1 (-1225 2625)(-1225 2350);
WIRE 16 -1 (-2125 2350)(-1225 2350);
FORCEPROP 2 LAST SIG_NAME VR_PVDDQ_GHJ_AIREF1
J 0
(-2115 2365);
DISPLAY 0.617021 (-2115 2365);
PAINT ORANGE (-2115 2365);
WIRE 16 -1 (-1275 2625)(-1225 2625);
WIRE 16 -1 (1050 2300)(-300 2300);
WIRE 16 -1 (-300 2800)(-300 2300);
WIRE 16 -1 (-2125 2300)(-300 2300);
FORCEPROP 2 LAST SIG_NAME VR_PVDDQ_GHJ_AIREF2
J 0
(-2115 2315);
DISPLAY 0.617021 (-2115 2315);
PAINT ORANGE (-2115 2315);
WIRE 16 -1 (-500 2800)(-300 2800);
WIRE 16 -1 (-325 550)(-325 1900);
WIRE 16 -1 (1050 1900)(-325 1900);
WIRE 16 -1 (-2125 1900)(-325 1900);
FORCEPROP 2 LAST SIG_NAME VR_PVDDQ_GHJ_AIINSEN
J 0
(-2135 1910);
DISPLAY 0.617021 (-2135 1910);
PAINT ORANGE (-2135 1910);
WIRE 16 -1 (-2125 2150)(1050 2150);
FORCEPROP 2 LAST SIG_NAME ISENSE_PVDDQ_GHJ_PH1_IMON
J 0
(-2150 2165);
DISPLAY 0.617021 (-2150 2165);
PAINT ORANGE (-2150 2165);
WIRE 16 -1 (-2125 2100)(1050 2100);
FORCEPROP 2 LAST SIG_NAME ISENSE_PVDDQ_GHJ_PH2_IMON
J 0
(-2150 2115);
DISPLAY 0.617021 (-2150 2115);
PAINT ORANGE (-2150 2115);
WIRE 16 -1 (1050 1950)(-2125 1950);
FORCEPROP 2 LAST SIG_NAME VR_PVDDQ_GHJ_VINSEN
J 0
(-2150 1965);
DISPLAY 0.617021 (-2150 1965);
PAINT ORANGE (-2150 1965);
WIRE 16 -1 (-325 2975)(-625 2975);
WIRE 16 -1 (-625 3250)(-625 2975);
WIRE 16 -1 (-2150 2975)(-625 2975);
FORCEPROP 0 LAST SIG_NAME SVID_CLK1_CPU1_R
J 0
(-2150 2985);
DISPLAY 0.617021 (-2150 2985);
PAINT ORANGE (-2150 2985);
WIRE 16 -1 (-700 2800)(-1675 2800);
WIRE 16 -1 (-1675 2800)(-1675 2625);
WIRE 16 -1 (-1475 2625)(-1675 2625);
WIRE 16 -1 (-1675 2625)(-2175 2625);
FORCEPROP 2 LAST SIG_NAME VR_PVDDQ_GHJ_VD12
J 0
(-2190 2640);
DISPLAY 0.617021 (-2190 2640);
PAINT ORANGE (-2190 2640);
WIRE 16 -1 (-1175 3550)(-1175 3600);
WIRE 16 -1 (-1175 3450)(-1175 3550);
WIRE 16 -1 (-1175 3550)(-1400 3550);
WIRE 16 -1 (-1400 3450)(-1400 3550);
WIRE 16 -1 (-1400 3550)(-2125 3550);
FORCEPROP 2 LAST SIG_NAME VR_PVDDQ_GHJ_VINSEN
J 0
(-2140 3565);
DISPLAY 0.617021 (-2140 3565);
PAINT ORANGE (-2140 3565);
WIRE 16 -1 (-1825 1075)(-2250 1075);
FORCEPROP 2 LAST SIG_NAME VSENSE_PVDDQ_GHJ_P
J 0
(-2265 1090);
DISPLAY 0.617021 (-2265 1090);
PAINT ORANGE (-2265 1090);
WIRE 16 -1 (-2125 1500)(-1600 1500);
FORCEPROP 2 LAST SIG_NAME FM_PVDDQ_GHJ_EN
J 0
(-2100 1510);
DISPLAY 0.617021 (-2100 1510);
PAINT ORANGE (-2100 1510);
DOT 1 (-1450 800);
DOT 1 (-1450 1075);
DOT 1 (-325 1900);
DOT 1 (-1675 2625);
DOT 1 (-1225 2350);
DOT 1 (-1400 3550);
DOT 1 (-1175 3550);
DOT 1 (-625 2975);
DOT 1 (-300 2300);
DOT 1 (175 1500);
DOT 1 (100 1800);
DOT 1 (900 3250);
DOT 1 (900 3625);
DOT 1 (1200 3250);
DOT 1 (2075 1000);
DOT 1 (3775 300);
DOT 1 (3925 1700);
DOT 1 (2200 2450);
DOT 1 (2400 2550);
DOT 1 (3050 2550);
DOT 1 (2400 3550);
DOT 1 (2475 3550);
FORCENOTE
ROOM=VDDQ_GHJ_PWR_VR
(-2730 -715) 0;
DISPLAY LEFT (-2730 -715);
DISPLAY 1.957447 (-2730 -715);
PAINT PURPLE (-2730 -715);
FORCENOTE
VOUT = 1.2V
(4075 3575) 0;
DISPLAY LEFT (4075 3575);
DISPLAY 0.808511 (4075 3575);
PAINT PURPLE (4075 3575);
FORCENOTE
DC TOL = +/-0.5%
(4075 3475) 0;
DISPLAY LEFT (4075 3475);
DISPLAY 0.808511 (4075 3475);
PAINT PURPLE (4075 3475);
FORCENOTE
AC & RIPPLE TOL = +/2.8%
(4075 3425) 0;
DISPLAY LEFT (4075 3425);
DISPLAY 0.808511 (4075 3425);
PAINT PURPLE (4075 3425);
FORCENOTE
IOUT TDC = 63A
(4075 3375) 0;
DISPLAY LEFT (4075 3375);
DISPLAY 0.808511 (4075 3375);
PAINT PURPLE (4075 3375);
FORCENOTE
IOUT PK = 74A
(4075 3325) 0;
DISPLAY LEFT (4075 3325);
DISPLAY 0.808511 (4075 3325);
PAINT PURPLE (4075 3325);
FORCENOTE
IOUT STEP = 45A
(4075 3275) 0;
DISPLAY LEFT (4075 3275);
DISPLAY 0.808511 (4075 3275);
PAINT PURPLE (4075 3275);
FORCENOTE
IOUT DI/DT = 15A/US
(4075 3225) 0;
DISPLAY LEFT (4075 3225);
DISPLAY 0.808511 (4075 3225);
PAINT PURPLE (4075 3225);
FORCENOTE
RIPPLE GUIDELINE = +/- 0.5%
(4075 3525) 0;
DISPLAY LEFT (4075 3525);
DISPLAY 0.808511 (4075 3525);
PAINT PURPLE (4075 3525);
FORCENOTE
SW FREQ = 833.33KHZ
(4075 3175) 0;
DISPLAY LEFT (4075 3175);
DISPLAY 0.808511 (4075 3175);
PAINT PURPLE (4075 3175);
QUIT
